FILE_TYPE = MACRO_DRAWING;
SET COLOR_WIRE YELLOW;
SET COLOR_PROP ORANGE;
SET COLOR_DOT WHITE;
SET COLOR_ARC YELLOW;
SET COLOR_BODY GREEN;
SET COLOR_NOTE PURPLE;
SET PROP_DISPLAY VALUE;
SET PAGE_NUMBER P162;
FORCEADD XC7A200T_2FBG484C_FBG484..3
(-9150 7450);
FORCEPROP 1 LAST $LOCATION U24
J 0
(-9100 7550);
DISPLAY 1.212766 (-9100 7550);
PAINT GREEN (-9100 7550);
FORCEPROP 0 LAST CDS_LOCATION U24
J 0
(-9100 7850);
DISPLAY 1.021277 (-9100 7850);
DISPLAY INVISIBLE (-9100 7850);
FORCEPROP 0 LAST $SEC 3
J 0
(-9100 7850);
DISPLAY 0.680851 (-9100 7850);
PAINT MONO (-9100 7850);
DISPLAY INVISIBLE (-9100 7850);
FORCEPROP 0 LAST CDS_SEC 3
J 0
(-9100 7850);
DISPLAY 1.021277 (-9100 7850);
DISPLAY INVISIBLE (-9100 7850);
FORCEPROP 0 LASTPIN (-9250 7350) $PN J16
J 2
(-9260 7360);
DISPLAY 0.680851 (-9260 7360);
PAINT MONO (-9260 7360);
FORCEPROP 0 LASTPIN (-6050 7350) $PN F15
J 0
(-6040 7360);
DISPLAY 0.680851 (-6040 7360);
PAINT MONO (-6040 7360);
FORCEPROP 0 LASTPIN (-9250 7150) $PN M17
J 2
(-9260 7160);
DISPLAY 0.680851 (-9260 7160);
PAINT MONO (-9260 7160);
FORCEPROP 0 LASTPIN (-6050 7150) $PN F21
J 0
(-6040 7160);
DISPLAY 0.680851 (-6040 7160);
PAINT MONO (-6040 7160);
FORCEPROP 0 LASTPIN (-6050 6850) $PN F14
J 0
(-6040 6860);
DISPLAY 0.680851 (-6040 6860);
PAINT MONO (-6040 6860);
FORCEPROP 0 LASTPIN (-9250 6850) $PN G13
J 2
(-9260 6860);
DISPLAY 0.680851 (-9260 6860);
PAINT MONO (-9260 6860);
FORCEPROP 0 LASTPIN (-6050 6950) $PN F13
J 0
(-6040 6960);
DISPLAY 0.680851 (-6040 6960);
PAINT MONO (-6040 6960);
FORCEPROP 0 LASTPIN (-9250 6950) $PN H13
J 2
(-9260 6960);
DISPLAY 0.680851 (-9260 6960);
PAINT MONO (-9260 6960);
FORCEPROP 0 LASTPIN (-6050 6650) $PN E17
J 0
(-6040 6660);
DISPLAY 0.680851 (-6040 6660);
PAINT MONO (-6040 6660);
FORCEPROP 0 LASTPIN (-9250 6650) $PN G16
J 2
(-9260 6660);
DISPLAY 0.680851 (-9260 6660);
PAINT MONO (-9260 6660);
FORCEPROP 0 LASTPIN (-6050 6750) $PN F16
J 0
(-6040 6760);
DISPLAY 0.680851 (-6040 6760);
PAINT MONO (-6040 6760);
FORCEPROP 0 LASTPIN (-9250 6750) $PN G15
J 2
(-9260 6760);
DISPLAY 0.680851 (-9260 6760);
PAINT MONO (-9260 6760);
FORCEPROP 0 LASTPIN (-6050 6450) $PN C15
J 0
(-6040 6460);
DISPLAY 0.680851 (-6040 6460);
PAINT MONO (-6040 6460);
FORCEPROP 0 LASTPIN (-9250 6450) $PN H14
J 2
(-9260 6460);
DISPLAY 0.680851 (-9260 6460);
PAINT MONO (-9260 6460);
FORCEPROP 0 LASTPIN (-6050 6550) $PN C14
J 0
(-6040 6560);
DISPLAY 0.680851 (-6040 6560);
PAINT MONO (-6040 6560);
FORCEPROP 0 LASTPIN (-9250 6550) $PN J14
J 2
(-9260 6560);
DISPLAY 0.680851 (-9260 6560);
PAINT MONO (-9260 6560);
FORCEPROP 0 LASTPIN (-9250 6250) $PN G18
J 2
(-9260 6260);
DISPLAY 0.680851 (-9260 6260);
PAINT MONO (-9260 6260);
FORCEPROP 0 LASTPIN (-6050 6250) $PN E14
J 0
(-6040 6260);
DISPLAY 0.680851 (-6040 6260);
PAINT MONO (-6040 6260);
FORCEPROP 0 LASTPIN (-9250 6350) $PN G17
J 2
(-9260 6360);
DISPLAY 0.680851 (-9260 6360);
PAINT MONO (-9260 6360);
FORCEPROP 0 LASTPIN (-6050 6350) $PN E13
J 0
(-6040 6360);
DISPLAY 0.680851 (-6040 6360);
PAINT MONO (-6040 6360);
FORCEPROP 0 LASTPIN (-6050 6050) $PN D16
J 0
(-6040 6060);
DISPLAY 0.680851 (-6040 6060);
PAINT MONO (-6040 6060);
FORCEPROP 0 LASTPIN (-9250 6050) $PN H15
J 2
(-9260 6060);
DISPLAY 0.680851 (-9260 6060);
PAINT MONO (-9260 6060);
FORCEPROP 0 LASTPIN (-6050 6150) $PN E16
J 0
(-6040 6160);
DISPLAY 0.680851 (-6040 6160);
PAINT MONO (-6040 6160);
FORCEPROP 0 LASTPIN (-9250 6150) $PN J15
J 2
(-9260 6160);
DISPLAY 0.680851 (-9260 6160);
PAINT MONO (-9260 6160);
FORCEPROP 0 LASTPIN (-9250 5850) $PN H18
J 2
(-9260 5860);
DISPLAY 0.680851 (-9260 5860);
PAINT MONO (-9260 5860);
FORCEPROP 0 LASTPIN (-6050 5850) $PN D15
J 0
(-6040 5860);
DISPLAY 0.680851 (-6040 5860);
PAINT MONO (-6040 5860);
FORCEPROP 0 LASTPIN (-9250 5950) $PN H17
J 2
(-9260 5960);
DISPLAY 0.680851 (-9260 5960);
PAINT MONO (-9260 5960);
FORCEPROP 0 LASTPIN (-6050 5950) $PN D14
J 0
(-6040 5960);
DISPLAY 0.680851 (-6040 5960);
PAINT MONO (-6040 5960);
FORCEPROP 0 LASTPIN (-6050 5650) $PN B16
J 0
(-6040 5660);
DISPLAY 0.680851 (-6040 5660);
PAINT MONO (-6040 5660);
FORCEPROP 0 LASTPIN (-9250 5650) $PN H22
J 2
(-9260 5660);
DISPLAY 0.680851 (-9260 5660);
PAINT MONO (-9260 5660);
FORCEPROP 0 LASTPIN (-6050 5750) $PN B15
J 0
(-6040 5760);
DISPLAY 0.680851 (-6040 5760);
PAINT MONO (-6040 5760);
FORCEPROP 0 LASTPIN (-9250 5750) $PN J22
J 2
(-9260 5760);
DISPLAY 0.680851 (-9260 5760);
PAINT MONO (-9260 5760);
FORCEPROP 0 LASTPIN (-6050 5450) $PN B13
J 0
(-6040 5460);
DISPLAY 0.680851 (-6040 5460);
PAINT MONO (-6040 5460);
FORCEPROP 0 LASTPIN (-9250 5450) $PN G20
J 2
(-9260 5460);
DISPLAY 0.680851 (-9260 5460);
PAINT MONO (-9260 5460);
FORCEPROP 0 LASTPIN (-6050 5550) $PN C13
J 0
(-6040 5560);
DISPLAY 0.680851 (-6040 5560);
PAINT MONO (-6040 5560);
FORCEPROP 0 LASTPIN (-9250 5550) $PN H20
J 2
(-9260 5560);
DISPLAY 0.680851 (-9260 5560);
PAINT MONO (-9260 5560);
FORCEPROP 0 LASTPIN (-6050 5250) $PN A16
J 0
(-6040 5260);
DISPLAY 0.680851 (-6040 5260);
PAINT MONO (-6040 5260);
FORCEPROP 0 LASTPIN (-9250 5250) $PN K22
J 2
(-9260 5260);
DISPLAY 0.680851 (-9260 5260);
PAINT MONO (-9260 5260);
FORCEPROP 0 LASTPIN (-6050 5350) $PN A15
J 0
(-6040 5360);
DISPLAY 0.680851 (-6040 5360);
PAINT MONO (-6040 5360);
FORCEPROP 0 LASTPIN (-9250 5350) $PN K21
J 2
(-9260 5360);
DISPLAY 0.680851 (-9260 5360);
PAINT MONO (-9260 5360);
FORCEPROP 0 LASTPIN (-6050 5050) $PN A14
J 0
(-6040 5060);
DISPLAY 0.680851 (-6040 5060);
PAINT MONO (-6040 5060);
FORCEPROP 0 LASTPIN (-9250 5050) $PN L21
J 2
(-9260 5060);
DISPLAY 0.680851 (-9260 5060);
PAINT MONO (-9260 5060);
FORCEPROP 0 LASTPIN (-6050 5150) $PN A13
J 0
(-6040 5160);
DISPLAY 0.680851 (-6040 5160);
PAINT MONO (-6040 5160);
FORCEPROP 0 LASTPIN (-9250 5150) $PN M21
J 2
(-9260 5160);
DISPLAY 0.680851 (-9260 5160);
PAINT MONO (-9260 5160);
FORCEPROP 0 LASTPIN (-9250 4850) $PN J21
J 2
(-9260 4860);
DISPLAY 0.680851 (-9260 4860);
PAINT MONO (-9260 4860);
FORCEPROP 0 LASTPIN (-6050 4850) $PN B18
J 0
(-6040 4860);
DISPLAY 0.680851 (-6040 4860);
PAINT MONO (-6040 4860);
FORCEPROP 0 LASTPIN (-9250 4950) $PN J20
J 2
(-9260 4960);
DISPLAY 0.680851 (-9260 4960);
PAINT MONO (-9260 4960);
FORCEPROP 0 LASTPIN (-6050 4950) $PN B17
J 0
(-6040 4960);
DISPLAY 0.680851 (-6040 4960);
PAINT MONO (-6040 4960);
FORCEPROP 0 LASTPIN (-9250 4650) $PN H19
J 2
(-9260 4660);
DISPLAY 0.680851 (-9260 4660);
PAINT MONO (-9260 4660);
FORCEPROP 0 LASTPIN (-6050 4650) $PN C17
J 0
(-6040 4660);
DISPLAY 0.680851 (-6040 4660);
PAINT MONO (-6040 4660);
FORCEPROP 0 LASTPIN (-9250 4750) $PN J19
J 2
(-9260 4760);
DISPLAY 0.680851 (-9260 4760);
PAINT MONO (-9260 4760);
FORCEPROP 0 LASTPIN (-6050 4750) $PN D17
J 0
(-6040 4760);
DISPLAY 0.680851 (-6040 4760);
PAINT MONO (-6040 4760);
FORCEPROP 0 LASTPIN (-9250 4450) $PN K19
J 2
(-9260 4460);
DISPLAY 0.680851 (-9260 4460);
PAINT MONO (-9260 4460);
FORCEPROP 0 LASTPIN (-6050 4450) $PN C19
J 0
(-6040 4460);
DISPLAY 0.680851 (-6040 4460);
PAINT MONO (-6040 4460);
FORCEPROP 0 LASTPIN (-9250 4550) $PN K18
J 2
(-9260 4560);
DISPLAY 0.680851 (-9260 4560);
PAINT MONO (-9260 4560);
FORCEPROP 0 LASTPIN (-6050 4550) $PN C18
J 0
(-6040 4560);
DISPLAY 0.680851 (-6040 4560);
PAINT MONO (-6040 4560);
FORCEPROP 0 LASTPIN (-9250 4250) $PN L20
J 2
(-9260 4260);
DISPLAY 0.680851 (-9260 4260);
PAINT MONO (-9260 4260);
FORCEPROP 0 LASTPIN (-6050 4250) $PN D19
J 0
(-6040 4260);
DISPLAY 0.680851 (-6040 4260);
PAINT MONO (-6040 4260);
FORCEPROP 0 LASTPIN (-9250 4350) $PN L19
J 2
(-9260 4360);
DISPLAY 0.680851 (-9260 4360);
PAINT MONO (-9260 4360);
FORCEPROP 0 LASTPIN (-6050 4350) $PN E19
J 0
(-6040 4360);
DISPLAY 0.680851 (-6040 4360);
PAINT MONO (-6040 4360);
FORCEPROP 0 LASTPIN (-6050 4050) $PN E18
J 0
(-6040 4060);
DISPLAY 0.680851 (-6040 4060);
PAINT MONO (-6040 4060);
FORCEPROP 0 LASTPIN (-9250 4050) $PN M22
J 2
(-9260 4060);
DISPLAY 0.680851 (-9260 4060);
PAINT MONO (-9260 4060);
FORCEPROP 0 LASTPIN (-9250 4150) $PN N22
J 2
(-9260 4160);
DISPLAY 0.680851 (-9260 4160);
PAINT MONO (-9260 4160);
FORCEPROP 0 LASTPIN (-6050 4150) $PN F18
J 0
(-6040 4160);
DISPLAY 0.680851 (-6040 4160);
PAINT MONO (-6040 4160);
FORCEPROP 0 LASTPIN (-6050 3850) $PN A20
J 0
(-6040 3860);
DISPLAY 0.680851 (-6040 3860);
PAINT MONO (-6040 3860);
FORCEPROP 0 LASTPIN (-9250 3850) $PN L18
J 2
(-9260 3860);
DISPLAY 0.680851 (-9260 3860);
PAINT MONO (-9260 3860);
FORCEPROP 0 LASTPIN (-6050 3950) $PN B20
J 0
(-6040 3960);
DISPLAY 0.680851 (-6040 3960);
PAINT MONO (-6040 3960);
FORCEPROP 0 LASTPIN (-9250 3950) $PN M18
J 2
(-9260 3960);
DISPLAY 0.680851 (-9260 3960);
PAINT MONO (-9260 3960);
FORCEPROP 0 LASTPIN (-6050 3650) $PN A19
J 0
(-6040 3660);
DISPLAY 0.680851 (-6040 3660);
PAINT MONO (-6040 3660);
FORCEPROP 0 LASTPIN (-9250 3650) $PN N19
J 2
(-9260 3660);
DISPLAY 0.680851 (-9260 3660);
PAINT MONO (-9260 3660);
FORCEPROP 0 LASTPIN (-6050 3750) $PN A18
J 0
(-6040 3760);
DISPLAY 0.680851 (-6040 3760);
PAINT MONO (-6040 3760);
FORCEPROP 0 LASTPIN (-9250 3750) $PN N18
J 2
(-9260 3760);
DISPLAY 0.680851 (-9260 3760);
PAINT MONO (-9260 3760);
FORCEPROP 0 LASTPIN (-6050 3450) $PN F20
J 0
(-6040 3460);
DISPLAY 0.680851 (-6040 3460);
PAINT MONO (-6040 3460);
FORCEPROP 0 LASTPIN (-9250 3450) $PN M20
J 2
(-9260 3460);
DISPLAY 0.680851 (-9260 3460);
PAINT MONO (-9260 3460);
FORCEPROP 0 LASTPIN (-6050 3550) $PN F19
J 0
(-6040 3560);
DISPLAY 0.680851 (-6040 3560);
PAINT MONO (-6040 3560);
FORCEPROP 0 LASTPIN (-9250 3550) $PN N20
J 2
(-9260 3560);
DISPLAY 0.680851 (-9260 3560);
PAINT MONO (-9260 3560);
FORCEPROP 0 LASTPIN (-9250 3250) $PN K14
J 2
(-9260 3260);
DISPLAY 0.680851 (-9260 3260);
PAINT MONO (-9260 3260);
FORCEPROP 0 LASTPIN (-6050 3250) $PN C20
J 0
(-6040 3260);
DISPLAY 0.680851 (-6040 3260);
PAINT MONO (-6040 3260);
FORCEPROP 0 LASTPIN (-6050 3350) $PN D20
J 0
(-6040 3360);
DISPLAY 0.680851 (-6040 3360);
PAINT MONO (-6040 3360);
FORCEPROP 0 LASTPIN (-9250 3350) $PN K13
J 2
(-9260 3360);
DISPLAY 0.680851 (-9260 3360);
PAINT MONO (-9260 3360);
FORCEPROP 0 LASTPIN (-6050 3050) $PN B22
J 0
(-6040 3060);
DISPLAY 0.680851 (-6040 3060);
PAINT MONO (-6040 3060);
FORCEPROP 0 LASTPIN (-9250 3050) $PN L13
J 2
(-9260 3060);
DISPLAY 0.680851 (-9260 3060);
PAINT MONO (-9260 3060);
FORCEPROP 0 LASTPIN (-6050 3150) $PN C22
J 0
(-6040 3160);
DISPLAY 0.680851 (-6040 3160);
PAINT MONO (-6040 3160);
FORCEPROP 0 LASTPIN (-9250 3150) $PN M13
J 2
(-9260 3160);
DISPLAY 0.680851 (-9260 3160);
PAINT MONO (-9260 3160);
FORCEPROP 0 LASTPIN (-6050 2850) $PN A21
J 0
(-6040 2860);
DISPLAY 0.680851 (-6040 2860);
PAINT MONO (-6040 2860);
FORCEPROP 0 LASTPIN (-9250 2850) $PN J17
J 2
(-9260 2860);
DISPLAY 0.680851 (-9260 2860);
PAINT MONO (-9260 2860);
FORCEPROP 0 LASTPIN (-9250 2950) $PN K17
J 2
(-9260 2960);
DISPLAY 0.680851 (-9260 2960);
PAINT MONO (-9260 2960);
FORCEPROP 0 LASTPIN (-6050 2950) $PN B21
J 0
(-6040 2960);
DISPLAY 0.680851 (-6040 2960);
PAINT MONO (-6040 2960);
FORCEPROP 0 LASTPIN (-6050 2650) $PN D22
J 0
(-6040 2660);
DISPLAY 0.680851 (-6040 2660);
PAINT MONO (-6040 2660);
FORCEPROP 0 LASTPIN (-9250 2650) $PN L15
J 2
(-9260 2660);
DISPLAY 0.680851 (-9260 2660);
PAINT MONO (-9260 2660);
FORCEPROP 0 LASTPIN (-6050 2750) $PN E22
J 0
(-6040 2760);
DISPLAY 0.680851 (-6040 2760);
PAINT MONO (-6040 2760);
FORCEPROP 0 LASTPIN (-9250 2750) $PN L14
J 2
(-9260 2760);
DISPLAY 0.680851 (-9260 2760);
PAINT MONO (-9260 2760);
FORCEPROP 0 LASTPIN (-6050 2450) $PN D21
J 0
(-6040 2460);
DISPLAY 0.680851 (-6040 2460);
PAINT MONO (-6040 2460);
FORCEPROP 0 LASTPIN (-9250 2450) $PN K16
J 2
(-9260 2460);
DISPLAY 0.680851 (-9260 2460);
PAINT MONO (-9260 2460);
FORCEPROP 0 LASTPIN (-6050 2550) $PN E21
J 0
(-6040 2560);
DISPLAY 0.680851 (-6040 2560);
PAINT MONO (-6040 2560);
FORCEPROP 0 LASTPIN (-9250 2550) $PN L16
J 2
(-9260 2560);
DISPLAY 0.680851 (-9260 2560);
PAINT MONO (-9260 2560);
FORCEPROP 0 LASTPIN (-6050 2250) $PN G22
J 0
(-6040 2260);
DISPLAY 0.680851 (-6040 2260);
PAINT MONO (-6040 2260);
FORCEPROP 0 LASTPIN (-9250 2250) $PN M16
J 2
(-9260 2260);
DISPLAY 0.680851 (-9260 2260);
PAINT MONO (-9260 2260);
FORCEPROP 0 LASTPIN (-6050 2350) $PN G21
J 0
(-6040 2360);
DISPLAY 0.680851 (-6040 2360);
PAINT MONO (-6040 2360);
FORCEPROP 0 LASTPIN (-9250 2350) $PN M15
J 2
(-9260 2360);
DISPLAY 0.680851 (-9260 2360);
PAINT MONO (-9260 2360);
FORCEPROP 1 LAST CLS_PN G240-10069-01
J 0
(-9100 7650);
DISPLAY 1.212766 (-9100 7650);
PAINT GREEN (-9100 7650);
FORCEPROP 2 LAST CDS_LIB pld
J 0
(-9150 7450);
DISPLAY INVISIBLE (-9150 7450);
FORCEPROP 1 LAST CDS_LMAN_SYM_OUTLINE 0,0,3000,-5400
J 0
(-9150 7450);
DISPLAY 0.468085 (-9150 7450);
PAINT GREEN (-9150 7450);
DISPLAY INVISIBLE (-9150 7450);
FORCEPROP 1 LAST PATH I228
J 0
(-9100 7500);
DISPLAY 1.212766 (-9100 7500);
PAINT GREEN (-9100 7500);
DISPLAY INVISIBLE (-9100 7500);
FORCEADD OFFPAGE_OUT..1
(-4050 5850);
FORCEPROP 2 LAST $XR0 26B3> 
J 0
(-3995 5850);
DISPLAY 0.638298 (-3995 5850);
PAINT MONO (-3995 5850);
FORCEPROP 1 LAST BODY_TYPE COMMENT
J 0
(-4040 5985);
DISPLAY 0.808511 (-4040 5985);
PAINT GREEN (-4040 5985);
DISPLAY INVISIBLE (-4040 5985);
FORCEPROP 1 LAST CDS_LMAN_SYM_OUTLINE -50,50,50,-50
J 0
(-4050 5850);
DISPLAY 0.468085 (-4050 5850);
PAINT GREEN (-4050 5850);
DISPLAY INVISIBLE (-4050 5850);
FORCEPROP 2 LAST CDS_LIB cls
J 0
(-4050 5850);
DISPLAY INVISIBLE (-4050 5850);
FORCEPROP 1 LAST OFFPAGE TRUE
J 0
(-4040 5905);
DISPLAY 0.808511 (-4040 5905);
PAINT GREEN (-4040 5905);
DISPLAY INVISIBLE (-4040 5905);
FORCEPROP 2 LAST PATH I230
J 0
(-3950 5900);
DISPLAY 1.021277 (-3950 5900);
DISPLAY INVISIBLE (-3950 5900);
FORCEADD OFFPAGE_OUT..1
(-4050 5950);
FORCEPROP 2 LAST $XR0 26C3> 
J 0
(-3995 5950);
DISPLAY 0.638298 (-3995 5950);
PAINT MONO (-3995 5950);
FORCEPROP 1 LAST BODY_TYPE COMMENT
J 0
(-4040 6085);
DISPLAY 0.808511 (-4040 6085);
PAINT GREEN (-4040 6085);
DISPLAY INVISIBLE (-4040 6085);
FORCEPROP 1 LAST CDS_LMAN_SYM_OUTLINE -50,50,50,-50
J 0
(-4050 5950);
DISPLAY 0.468085 (-4050 5950);
PAINT GREEN (-4050 5950);
DISPLAY INVISIBLE (-4050 5950);
FORCEPROP 2 LAST CDS_LIB cls
J 0
(-4050 5950);
DISPLAY INVISIBLE (-4050 5950);
FORCEPROP 1 LAST OFFPAGE TRUE
J 0
(-4040 6005);
DISPLAY 0.808511 (-4040 6005);
PAINT GREEN (-4040 6005);
DISPLAY INVISIBLE (-4040 6005);
FORCEPROP 2 LAST PATH I231
J 0
(-3950 6000);
DISPLAY 1.021277 (-3950 6000);
DISPLAY INVISIBLE (-3950 6000);
FORCEADD OFFPAGE_OUT..1
(-4050 5550);
FORCEPROP 2 LAST $XR0 26C3> 
J 0
(-3995 5550);
DISPLAY 0.638298 (-3995 5550);
PAINT MONO (-3995 5550);
FORCEPROP 1 LAST CDS_LMAN_SYM_OUTLINE -50,50,50,-50
J 0
(-4050 5550);
DISPLAY 0.468085 (-4050 5550);
PAINT GREEN (-4050 5550);
DISPLAY INVISIBLE (-4050 5550);
FORCEPROP 2 LAST CDS_LIB cls
J 0
(-4050 5550);
DISPLAY INVISIBLE (-4050 5550);
FORCEPROP 1 LAST BODY_TYPE COMMENT
J 0
(-4040 5685);
DISPLAY 0.808511 (-4040 5685);
PAINT GREEN (-4040 5685);
DISPLAY INVISIBLE (-4040 5685);
FORCEPROP 1 LAST OFFPAGE TRUE
J 0
(-4040 5605);
DISPLAY 0.808511 (-4040 5605);
PAINT GREEN (-4040 5605);
DISPLAY INVISIBLE (-4040 5605);
FORCEPROP 2 LAST PATH I236
J 0
(-3950 5600);
DISPLAY 1.021277 (-3950 5600);
DISPLAY INVISIBLE (-3950 5600);
FORCEADD OFFPAGE_OUT..1
(-4050 5450);
FORCEPROP 2 LAST $XR0 26C3> 
J 0
(-3995 5450);
DISPLAY 0.638298 (-3995 5450);
PAINT MONO (-3995 5450);
FORCEPROP 1 LAST CDS_LMAN_SYM_OUTLINE -50,50,50,-50
J 0
(-4050 5450);
DISPLAY 0.468085 (-4050 5450);
PAINT GREEN (-4050 5450);
DISPLAY INVISIBLE (-4050 5450);
FORCEPROP 2 LAST CDS_LIB cls
J 0
(-4050 5450);
DISPLAY INVISIBLE (-4050 5450);
FORCEPROP 1 LAST BODY_TYPE COMMENT
J 0
(-4040 5585);
DISPLAY 0.808511 (-4040 5585);
PAINT GREEN (-4040 5585);
DISPLAY INVISIBLE (-4040 5585);
FORCEPROP 1 LAST OFFPAGE TRUE
J 0
(-4040 5505);
DISPLAY 0.808511 (-4040 5505);
PAINT GREEN (-4040 5505);
DISPLAY INVISIBLE (-4040 5505);
FORCEPROP 2 LAST PATH I237
J 0
(-3950 5500);
DISPLAY 1.021277 (-3950 5500);
DISPLAY INVISIBLE (-3950 5500);
FORCEADD OFFPAGE_IN..2
R 2
(-11300 4950);
FORCEPROP 2 LAST $XR0 9H15> 
J 0
(-11483 4950);
DISPLAY 0.638298 (-11483 4950);
PAINT MONO (-11483 4950);
FORCEPROP 2 LAST PATH I239
J 0
(-11450 5000);
DISPLAY 1.021277 (-11450 5000);
DISPLAY INVISIBLE (-11450 5000);
FORCEPROP 1 LAST OFFPAGE TRUE
J 2
(-11310 5005);
DISPLAY 0.808511 (-11310 5005);
PAINT GREEN (-11310 5005);
DISPLAY INVISIBLE (-11310 5005);
FORCEPROP 1 LAST BODY_TYPE COMMENT
J 2
(-11310 5085);
DISPLAY 0.808511 (-11310 5085);
PAINT GREEN (-11310 5085);
DISPLAY INVISIBLE (-11310 5085);
FORCEPROP 1 LAST CDS_LMAN_SYM_OUTLINE -50,50,50,-50
J 2
(-11300 4950);
DISPLAY 0.468085 (-11300 4950);
PAINT GREEN (-11300 4950);
DISPLAY INVISIBLE (-11300 4950);
FORCEPROP 2 LAST CDS_LIB cls
J 0
(-11300 4950);
DISPLAY INVISIBLE (-11300 4950);
FORCEADD OFFPAGE_BI..1
R 6
(-5250 3150);
FORCEPROP 2 LAST $XR0 25C3<> 
J 0
(-5190 3150);
DISPLAY 0.638298 (-5190 3150);
PAINT MONO (-5190 3150);
FORCEPROP 2 LAST CDS_LIB cls
J 0
(-5250 3150);
DISPLAY INVISIBLE (-5250 3150);
FORCEPROP 1 LAST CDS_LMAN_SYM_OUTLINE -50,50,50,-50
J 0
(-5250 3150);
DISPLAY 0.468085 (-5250 3150);
PAINT GREEN (-5250 3150);
DISPLAY INVISIBLE (-5250 3150);
FORCEPROP 1 LAST BODY_TYPE COMMENT
J 0
(-5240 2977);
DISPLAY 0.808511 (-5240 2977);
PAINT GREEN (-5240 2977);
DISPLAY INVISIBLE (-5240 2977);
FORCEPROP 1 LAST OFFPAGE TRUE
J 0
(-5240 3057);
DISPLAY 0.808511 (-5240 3057);
PAINT GREEN (-5240 3057);
DISPLAY INVISIBLE (-5240 3057);
FORCEPROP 2 LAST PATH I318
J 0
(-5200 3250);
DISPLAY 1.021277 (-5200 3250);
DISPLAY INVISIBLE (-5200 3250);
FORCEADD OFFPAGE_BI..1
R 6
(-5250 3050);
FORCEPROP 2 LAST $XR0 25C3<> 
J 0
(-5190 3050);
DISPLAY 0.638298 (-5190 3050);
PAINT MONO (-5190 3050);
FORCEPROP 2 LAST CDS_LIB cls
J 0
(-5250 3050);
DISPLAY INVISIBLE (-5250 3050);
FORCEPROP 1 LAST CDS_LMAN_SYM_OUTLINE -50,50,50,-50
J 0
(-5250 3050);
DISPLAY 0.468085 (-5250 3050);
PAINT GREEN (-5250 3050);
DISPLAY INVISIBLE (-5250 3050);
FORCEPROP 1 LAST BODY_TYPE COMMENT
J 0
(-5240 2877);
DISPLAY 0.808511 (-5240 2877);
PAINT GREEN (-5240 2877);
DISPLAY INVISIBLE (-5240 2877);
FORCEPROP 1 LAST OFFPAGE TRUE
J 0
(-5240 2957);
DISPLAY 0.808511 (-5240 2957);
PAINT GREEN (-5240 2957);
DISPLAY INVISIBLE (-5240 2957);
FORCEPROP 2 LAST PATH I319
J 0
(-5200 3150);
DISPLAY 1.021277 (-5200 3150);
DISPLAY INVISIBLE (-5200 3150);
FORCEADD OFFPAGE_BI..1
R 6
(-5250 2950);
FORCEPROP 2 LAST $XR0 25C3<> 
J 0
(-5190 2950);
DISPLAY 0.638298 (-5190 2950);
PAINT MONO (-5190 2950);
FORCEPROP 2 LAST CDS_LIB cls
J 0
(-5250 2950);
DISPLAY INVISIBLE (-5250 2950);
FORCEPROP 1 LAST CDS_LMAN_SYM_OUTLINE -50,50,50,-50
J 0
(-5250 2950);
DISPLAY 0.468085 (-5250 2950);
PAINT GREEN (-5250 2950);
DISPLAY INVISIBLE (-5250 2950);
FORCEPROP 1 LAST BODY_TYPE COMMENT
J 0
(-5240 2777);
DISPLAY 0.808511 (-5240 2777);
PAINT GREEN (-5240 2777);
DISPLAY INVISIBLE (-5240 2777);
FORCEPROP 1 LAST OFFPAGE TRUE
J 0
(-5240 2857);
DISPLAY 0.808511 (-5240 2857);
PAINT GREEN (-5240 2857);
DISPLAY INVISIBLE (-5240 2857);
FORCEPROP 2 LAST PATH I320
J 0
(-5200 3050);
DISPLAY 1.021277 (-5200 3050);
DISPLAY INVISIBLE (-5200 3050);
FORCEADD OFFPAGE_BI..1
R 6
(-5250 2850);
FORCEPROP 2 LAST $XR0 25C3<> 
J 0
(-5190 2850);
DISPLAY 0.638298 (-5190 2850);
PAINT MONO (-5190 2850);
FORCEPROP 2 LAST CDS_LIB cls
J 0
(-5250 2850);
DISPLAY INVISIBLE (-5250 2850);
FORCEPROP 1 LAST CDS_LMAN_SYM_OUTLINE -50,50,50,-50
J 0
(-5250 2850);
DISPLAY 0.468085 (-5250 2850);
PAINT GREEN (-5250 2850);
DISPLAY INVISIBLE (-5250 2850);
FORCEPROP 1 LAST BODY_TYPE COMMENT
J 0
(-5240 2677);
DISPLAY 0.808511 (-5240 2677);
PAINT GREEN (-5240 2677);
DISPLAY INVISIBLE (-5240 2677);
FORCEPROP 1 LAST OFFPAGE TRUE
J 0
(-5240 2757);
DISPLAY 0.808511 (-5240 2757);
PAINT GREEN (-5240 2757);
DISPLAY INVISIBLE (-5240 2757);
FORCEPROP 2 LAST PATH I321
J 0
(-5200 2950);
DISPLAY 1.021277 (-5200 2950);
DISPLAY INVISIBLE (-5200 2950);
FORCEADD OFFPAGE_BI..1
R 6
(-5250 2750);
FORCEPROP 2 LAST $XR0 25C3<> 
J 0
(-5190 2750);
DISPLAY 0.638298 (-5190 2750);
PAINT MONO (-5190 2750);
FORCEPROP 2 LAST CDS_LIB cls
J 0
(-5250 2750);
DISPLAY INVISIBLE (-5250 2750);
FORCEPROP 1 LAST CDS_LMAN_SYM_OUTLINE -50,50,50,-50
J 0
(-5250 2750);
DISPLAY 0.468085 (-5250 2750);
PAINT GREEN (-5250 2750);
DISPLAY INVISIBLE (-5250 2750);
FORCEPROP 1 LAST BODY_TYPE COMMENT
J 0
(-5240 2577);
DISPLAY 0.808511 (-5240 2577);
PAINT GREEN (-5240 2577);
DISPLAY INVISIBLE (-5240 2577);
FORCEPROP 1 LAST OFFPAGE TRUE
J 0
(-5240 2657);
DISPLAY 0.808511 (-5240 2657);
PAINT GREEN (-5240 2657);
DISPLAY INVISIBLE (-5240 2657);
FORCEPROP 2 LAST PATH I322
J 0
(-5200 2850);
DISPLAY 1.021277 (-5200 2850);
DISPLAY INVISIBLE (-5200 2850);
FORCEADD OFFPAGE_BI..1
R 6
(-5250 2650);
FORCEPROP 2 LAST $XR0 25C3<> 
J 0
(-5190 2650);
DISPLAY 0.638298 (-5190 2650);
PAINT MONO (-5190 2650);
FORCEPROP 2 LAST CDS_LIB cls
J 0
(-5250 2650);
DISPLAY INVISIBLE (-5250 2650);
FORCEPROP 1 LAST CDS_LMAN_SYM_OUTLINE -50,50,50,-50
J 0
(-5250 2650);
DISPLAY 0.468085 (-5250 2650);
PAINT GREEN (-5250 2650);
DISPLAY INVISIBLE (-5250 2650);
FORCEPROP 1 LAST BODY_TYPE COMMENT
J 0
(-5240 2477);
DISPLAY 0.808511 (-5240 2477);
PAINT GREEN (-5240 2477);
DISPLAY INVISIBLE (-5240 2477);
FORCEPROP 1 LAST OFFPAGE TRUE
J 0
(-5240 2557);
DISPLAY 0.808511 (-5240 2557);
PAINT GREEN (-5240 2557);
DISPLAY INVISIBLE (-5240 2557);
FORCEPROP 2 LAST PATH I323
J 0
(-5200 2750);
DISPLAY 1.021277 (-5200 2750);
DISPLAY INVISIBLE (-5200 2750);
FORCEADD OFFPAGE_BI..1
R 6
(-5250 2550);
FORCEPROP 2 LAST $XR0 25C3<> 
J 0
(-5190 2550);
DISPLAY 0.638298 (-5190 2550);
PAINT MONO (-5190 2550);
FORCEPROP 2 LAST CDS_LIB cls
J 0
(-5250 2550);
DISPLAY INVISIBLE (-5250 2550);
FORCEPROP 1 LAST CDS_LMAN_SYM_OUTLINE -50,50,50,-50
J 0
(-5250 2550);
DISPLAY 0.468085 (-5250 2550);
PAINT GREEN (-5250 2550);
DISPLAY INVISIBLE (-5250 2550);
FORCEPROP 1 LAST BODY_TYPE COMMENT
J 0
(-5240 2377);
DISPLAY 0.808511 (-5240 2377);
PAINT GREEN (-5240 2377);
DISPLAY INVISIBLE (-5240 2377);
FORCEPROP 1 LAST OFFPAGE TRUE
J 0
(-5240 2457);
DISPLAY 0.808511 (-5240 2457);
PAINT GREEN (-5240 2457);
DISPLAY INVISIBLE (-5240 2457);
FORCEPROP 2 LAST PATH I324
J 0
(-5200 2650);
DISPLAY 1.021277 (-5200 2650);
DISPLAY INVISIBLE (-5200 2650);
FORCEADD OFFPAGE_BI..1
R 6
(-5250 2450);
FORCEPROP 2 LAST $XR0 25C3<> 
J 0
(-5190 2450);
DISPLAY 0.638298 (-5190 2450);
PAINT MONO (-5190 2450);
FORCEPROP 2 LAST CDS_LIB cls
J 0
(-5250 2450);
DISPLAY INVISIBLE (-5250 2450);
FORCEPROP 1 LAST CDS_LMAN_SYM_OUTLINE -50,50,50,-50
J 0
(-5250 2450);
DISPLAY 0.468085 (-5250 2450);
PAINT GREEN (-5250 2450);
DISPLAY INVISIBLE (-5250 2450);
FORCEPROP 1 LAST BODY_TYPE COMMENT
J 0
(-5240 2277);
DISPLAY 0.808511 (-5240 2277);
PAINT GREEN (-5240 2277);
DISPLAY INVISIBLE (-5240 2277);
FORCEPROP 1 LAST OFFPAGE TRUE
J 0
(-5240 2357);
DISPLAY 0.808511 (-5240 2357);
PAINT GREEN (-5240 2357);
DISPLAY INVISIBLE (-5240 2357);
FORCEPROP 2 LAST PATH I325
J 0
(-5200 2550);
DISPLAY 1.021277 (-5200 2550);
DISPLAY INVISIBLE (-5200 2550);
FORCEADD OFFPAGE_BI..1
R 6
(-5250 2350);
FORCEPROP 2 LAST $XR0 25D3<> 
J 0
(-5190 2350);
DISPLAY 0.638298 (-5190 2350);
PAINT MONO (-5190 2350);
FORCEPROP 2 LAST CDS_LIB cls
J 0
(-5250 2350);
DISPLAY INVISIBLE (-5250 2350);
FORCEPROP 1 LAST CDS_LMAN_SYM_OUTLINE -50,50,50,-50
J 0
(-5250 2350);
DISPLAY 0.468085 (-5250 2350);
PAINT GREEN (-5250 2350);
DISPLAY INVISIBLE (-5250 2350);
FORCEPROP 1 LAST BODY_TYPE COMMENT
J 0
(-5240 2177);
DISPLAY 0.808511 (-5240 2177);
PAINT GREEN (-5240 2177);
DISPLAY INVISIBLE (-5240 2177);
FORCEPROP 1 LAST OFFPAGE TRUE
J 0
(-5240 2257);
DISPLAY 0.808511 (-5240 2257);
PAINT GREEN (-5240 2257);
DISPLAY INVISIBLE (-5240 2257);
FORCEPROP 2 LAST PATH I326
J 0
(-5200 2450);
DISPLAY 1.021277 (-5200 2450);
DISPLAY INVISIBLE (-5200 2450);
FORCEADD OFFPAGE_BI..1
R 6
(-5250 2250);
FORCEPROP 2 LAST $XR0 25D3<> 
J 0
(-5190 2250);
DISPLAY 0.638298 (-5190 2250);
PAINT MONO (-5190 2250);
FORCEPROP 2 LAST CDS_LIB cls
J 0
(-5250 2250);
DISPLAY INVISIBLE (-5250 2250);
FORCEPROP 1 LAST CDS_LMAN_SYM_OUTLINE -50,50,50,-50
J 0
(-5250 2250);
DISPLAY 0.468085 (-5250 2250);
PAINT GREEN (-5250 2250);
DISPLAY INVISIBLE (-5250 2250);
FORCEPROP 1 LAST BODY_TYPE COMMENT
J 0
(-5240 2077);
DISPLAY 0.808511 (-5240 2077);
PAINT GREEN (-5240 2077);
DISPLAY INVISIBLE (-5240 2077);
FORCEPROP 1 LAST OFFPAGE TRUE
J 0
(-5240 2157);
DISPLAY 0.808511 (-5240 2157);
PAINT GREEN (-5240 2157);
DISPLAY INVISIBLE (-5240 2157);
FORCEPROP 2 LAST PATH I327
J 0
(-5200 2350);
DISPLAY 1.021277 (-5200 2350);
DISPLAY INVISIBLE (-5200 2350);
FORCEADD OFFPAGE_OUT..1
R 2
(-11300 2250);
FORCEPROP 2 LAST $XR0 21L8< 
J 0
(-11483 2250);
DISPLAY 0.638298 (-11483 2250);
PAINT MONO (-11483 2250);
FORCEPROP 2 LAST PATH I338
J 0
(-11250 2350);
DISPLAY 1.021277 (-11250 2350);
DISPLAY INVISIBLE (-11250 2350);
FORCEPROP 1 LAST OFFPAGE TRUE
J 2
(-11310 2305);
DISPLAY 0.808511 (-11310 2305);
PAINT GREEN (-11310 2305);
DISPLAY INVISIBLE (-11310 2305);
FORCEPROP 2 LAST CDS_LIB cls
J 0
(-11300 2250);
DISPLAY INVISIBLE (-11300 2250);
FORCEPROP 1 LAST CDS_LMAN_SYM_OUTLINE -50,50,50,-50
J 2
(-11300 2250);
DISPLAY 0.468085 (-11300 2250);
PAINT GREEN (-11300 2250);
DISPLAY INVISIBLE (-11300 2250);
FORCEPROP 1 LAST BODY_TYPE COMMENT
J 2
(-11310 2385);
DISPLAY 0.808511 (-11310 2385);
PAINT GREEN (-11310 2385);
DISPLAY INVISIBLE (-11310 2385);
FORCEADD OFFPAGE_IN..2
R 2
(-11300 2350);
FORCEPROP 2 LAST $XR0 21H14> 
J 0
(-11514 2350);
DISPLAY 0.638298 (-11514 2350);
PAINT MONO (-11514 2350);
FORCEPROP 2 LAST PATH I339
J 0
(-11250 2450);
DISPLAY 1.021277 (-11250 2450);
DISPLAY INVISIBLE (-11250 2450);
FORCEPROP 1 LAST OFFPAGE TRUE
J 2
(-11310 2405);
DISPLAY 0.808511 (-11310 2405);
PAINT GREEN (-11310 2405);
DISPLAY INVISIBLE (-11310 2405);
FORCEPROP 1 LAST CDS_LMAN_SYM_OUTLINE -50,50,50,-50
J 2
(-11300 2350);
DISPLAY 0.468085 (-11300 2350);
PAINT GREEN (-11300 2350);
DISPLAY INVISIBLE (-11300 2350);
FORCEPROP 2 LAST CDS_LIB cls
J 0
(-11300 2350);
DISPLAY INVISIBLE (-11300 2350);
FORCEPROP 1 LAST BODY_TYPE COMMENT
J 2
(-11310 2485);
DISPLAY 0.808511 (-11310 2485);
PAINT GREEN (-11310 2485);
DISPLAY INVISIBLE (-11310 2485);
FORCEADD OFFPAGE_OUT..1
(-4050 5150);
FORCEPROP 2 LAST $XR0 26D3> 
J 0
(-3995 5150);
DISPLAY 0.638298 (-3995 5150);
PAINT MONO (-3995 5150);
FORCEPROP 1 LAST BODY_TYPE COMMENT
J 0
(-4040 5285);
DISPLAY 0.808511 (-4040 5285);
PAINT GREEN (-4040 5285);
DISPLAY INVISIBLE (-4040 5285);
FORCEPROP 1 LAST CDS_LMAN_SYM_OUTLINE -50,50,50,-50
J 0
(-4050 5150);
DISPLAY 0.468085 (-4050 5150);
PAINT GREEN (-4050 5150);
DISPLAY INVISIBLE (-4050 5150);
FORCEPROP 2 LAST CDS_LIB cls
J 0
(-4050 5150);
DISPLAY INVISIBLE (-4050 5150);
FORCEPROP 1 LAST OFFPAGE TRUE
J 0
(-4040 5205);
DISPLAY 0.808511 (-4040 5205);
PAINT GREEN (-4040 5205);
DISPLAY INVISIBLE (-4040 5205);
FORCEPROP 2 LAST PATH I346
J 0
(-4000 5250);
DISPLAY 1.021277 (-4000 5250);
DISPLAY INVISIBLE (-4000 5250);
FORCEADD OFFPAGE_OUT..1
(-4050 5050);
FORCEPROP 2 LAST $XR0 26D3> 
J 0
(-3995 5050);
DISPLAY 0.638298 (-3995 5050);
PAINT MONO (-3995 5050);
FORCEPROP 1 LAST BODY_TYPE COMMENT
J 0
(-4040 5185);
DISPLAY 0.808511 (-4040 5185);
PAINT GREEN (-4040 5185);
DISPLAY INVISIBLE (-4040 5185);
FORCEPROP 1 LAST CDS_LMAN_SYM_OUTLINE -50,50,50,-50
J 0
(-4050 5050);
DISPLAY 0.468085 (-4050 5050);
PAINT GREEN (-4050 5050);
DISPLAY INVISIBLE (-4050 5050);
FORCEPROP 2 LAST CDS_LIB cls
J 0
(-4050 5050);
DISPLAY INVISIBLE (-4050 5050);
FORCEPROP 1 LAST OFFPAGE TRUE
J 0
(-4040 5105);
DISPLAY 0.808511 (-4040 5105);
PAINT GREEN (-4040 5105);
DISPLAY INVISIBLE (-4040 5105);
FORCEPROP 2 LAST PATH I347
J 0
(-4000 5150);
DISPLAY 1.021277 (-4000 5150);
DISPLAY INVISIBLE (-4000 5150);
FORCEADD OFFPAGE_IN..2
R 2
(-11300 3650);
FORCEPROP 2 LAST $XR0 10H10> 
J 0
(-11514 3650);
DISPLAY 0.638298 (-11514 3650);
PAINT MONO (-11514 3650);
FORCEPROP 2 LAST PATH I354
J 0
(-11450 3700);
DISPLAY 1.021277 (-11450 3700);
DISPLAY INVISIBLE (-11450 3700);
FORCEPROP 1 LAST OFFPAGE TRUE
J 2
(-11310 3705);
DISPLAY 0.808511 (-11310 3705);
PAINT GREEN (-11310 3705);
DISPLAY INVISIBLE (-11310 3705);
FORCEPROP 2 LAST CDS_LIB cls
J 0
(-11300 3650);
DISPLAY INVISIBLE (-11300 3650);
FORCEPROP 1 LAST CDS_LMAN_SYM_OUTLINE -50,50,50,-50
J 2
(-11300 3650);
DISPLAY 0.468085 (-11300 3650);
PAINT GREEN (-11300 3650);
DISPLAY INVISIBLE (-11300 3650);
FORCEPROP 1 LAST BODY_TYPE COMMENT
J 2
(-11310 3785);
DISPLAY 0.808511 (-11310 3785);
PAINT GREEN (-11310 3785);
DISPLAY INVISIBLE (-11310 3785);
FORCEADD OFFPAGE_IN..2
R 2
(-11300 3750);
FORCEPROP 2 LAST $XR0 10H10> 
J 0
(-11514 3750);
DISPLAY 0.638298 (-11514 3750);
PAINT MONO (-11514 3750);
FORCEPROP 2 LAST PATH I355
J 0
(-11450 3800);
DISPLAY 1.021277 (-11450 3800);
DISPLAY INVISIBLE (-11450 3800);
FORCEPROP 1 LAST OFFPAGE TRUE
J 2
(-11310 3805);
DISPLAY 0.808511 (-11310 3805);
PAINT GREEN (-11310 3805);
DISPLAY INVISIBLE (-11310 3805);
FORCEPROP 2 LAST CDS_LIB cls
J 0
(-11300 3750);
DISPLAY INVISIBLE (-11300 3750);
FORCEPROP 1 LAST CDS_LMAN_SYM_OUTLINE -50,50,50,-50
J 2
(-11300 3750);
DISPLAY 0.468085 (-11300 3750);
PAINT GREEN (-11300 3750);
DISPLAY INVISIBLE (-11300 3750);
FORCEPROP 1 LAST BODY_TYPE COMMENT
J 2
(-11310 3885);
DISPLAY 0.808511 (-11310 3885);
PAINT GREEN (-11310 3885);
DISPLAY INVISIBLE (-11310 3885);
FORCEADD OFFPAGE_IN..2
R 2
(-11300 3550);
FORCEPROP 2 LAST $XR0 10H10> 
J 0
(-11514 3550);
DISPLAY 0.638298 (-11514 3550);
PAINT MONO (-11514 3550);
FORCEPROP 2 LAST PATH I356
J 0
(-11450 3600);
DISPLAY 1.021277 (-11450 3600);
DISPLAY INVISIBLE (-11450 3600);
FORCEPROP 1 LAST OFFPAGE TRUE
J 2
(-11310 3605);
DISPLAY 0.808511 (-11310 3605);
PAINT GREEN (-11310 3605);
DISPLAY INVISIBLE (-11310 3605);
FORCEPROP 1 LAST BODY_TYPE COMMENT
J 2
(-11310 3685);
DISPLAY 0.808511 (-11310 3685);
PAINT GREEN (-11310 3685);
DISPLAY INVISIBLE (-11310 3685);
FORCEPROP 1 LAST CDS_LMAN_SYM_OUTLINE -50,50,50,-50
J 2
(-11300 3550);
DISPLAY 0.468085 (-11300 3550);
PAINT GREEN (-11300 3550);
DISPLAY INVISIBLE (-11300 3550);
FORCEPROP 2 LAST CDS_LIB cls
J 0
(-11300 3550);
DISPLAY INVISIBLE (-11300 3550);
FORCEADD OFFPAGE_IN..2
R 2
(-11300 4150);
FORCEPROP 2 LAST $XR0 17D12> 
J 0
(-11514 4150);
DISPLAY 0.638298 (-11514 4150);
PAINT MONO (-11514 4150);
FORCEPROP 2 LAST $XR1 25D6<> 
J 0
(-11724 4150);
DISPLAY 0.638298 (-11724 4150);
PAINT MONO (-11724 4150);
FORCEPROP 2 LAST PATH I399
J 0
(-11500 4200);
DISPLAY 1.021277 (-11500 4200);
DISPLAY INVISIBLE (-11500 4200);
FORCEPROP 1 LAST OFFPAGE TRUE
J 2
(-11310 4205);
DISPLAY 0.808511 (-11310 4205);
PAINT GREEN (-11310 4205);
DISPLAY INVISIBLE (-11310 4205);
FORCEPROP 1 LAST CDS_LMAN_SYM_OUTLINE -50,50,50,-50
J 2
(-11300 4150);
DISPLAY 0.468085 (-11300 4150);
PAINT GREEN (-11300 4150);
DISPLAY INVISIBLE (-11300 4150);
FORCEPROP 2 LAST CDS_LIB cls
J 0
(-11300 4150);
DISPLAY INVISIBLE (-11300 4150);
FORCEPROP 1 LAST BODY_TYPE COMMENT
J 2
(-11310 4285);
DISPLAY 0.808511 (-11310 4285);
PAINT GREEN (-11310 4285);
DISPLAY INVISIBLE (-11310 4285);
FORCEADD OFFPAGE_IN..2
R 2
(-11300 4050);
FORCEPROP 2 LAST $XR0 17G12> 
J 0
(-11514 4050);
DISPLAY 0.638298 (-11514 4050);
PAINT MONO (-11514 4050);
FORCEPROP 2 LAST $XR1 25D6<> 
J 0
(-11724 4050);
DISPLAY 0.638298 (-11724 4050);
PAINT MONO (-11724 4050);
FORCEPROP 2 LAST PATH I400
J 0
(-11500 4100);
DISPLAY 1.021277 (-11500 4100);
DISPLAY INVISIBLE (-11500 4100);
FORCEPROP 1 LAST OFFPAGE TRUE
J 2
(-11310 4105);
DISPLAY 0.808511 (-11310 4105);
PAINT GREEN (-11310 4105);
DISPLAY INVISIBLE (-11310 4105);
FORCEPROP 1 LAST CDS_LMAN_SYM_OUTLINE -50,50,50,-50
J 2
(-11300 4050);
DISPLAY 0.468085 (-11300 4050);
PAINT GREEN (-11300 4050);
DISPLAY INVISIBLE (-11300 4050);
FORCEPROP 2 LAST CDS_LIB cls
J 0
(-11300 4050);
DISPLAY INVISIBLE (-11300 4050);
FORCEPROP 1 LAST BODY_TYPE COMMENT
J 2
(-11310 4185);
DISPLAY 0.808511 (-11310 4185);
PAINT GREEN (-11310 4185);
DISPLAY INVISIBLE (-11310 4185);
FORCEADD OFFPAGE_IN..2
R 2
(-11300 3950);
FORCEPROP 2 LAST $XR0 17K12> 
J 0
(-11514 3950);
DISPLAY 0.638298 (-11514 3950);
PAINT MONO (-11514 3950);
FORCEPROP 2 LAST $XR1 25D6<> 
J 0
(-11724 3950);
DISPLAY 0.638298 (-11724 3950);
PAINT MONO (-11724 3950);
FORCEPROP 2 LAST PATH I401
J 0
(-11500 4000);
DISPLAY 1.021277 (-11500 4000);
DISPLAY INVISIBLE (-11500 4000);
FORCEPROP 1 LAST OFFPAGE TRUE
J 2
(-11310 4005);
DISPLAY 0.808511 (-11310 4005);
PAINT GREEN (-11310 4005);
DISPLAY INVISIBLE (-11310 4005);
FORCEPROP 1 LAST BODY_TYPE COMMENT
J 2
(-11310 4085);
DISPLAY 0.808511 (-11310 4085);
PAINT GREEN (-11310 4085);
DISPLAY INVISIBLE (-11310 4085);
FORCEPROP 2 LAST CDS_LIB cls
J 0
(-11300 3950);
DISPLAY INVISIBLE (-11300 3950);
FORCEPROP 1 LAST CDS_LMAN_SYM_OUTLINE -50,50,50,-50
J 2
(-11300 3950);
DISPLAY 0.468085 (-11300 3950);
PAINT GREEN (-11300 3950);
DISPLAY INVISIBLE (-11300 3950);
FORCEADD OFFPAGE_OUT..1
R 2
(-11300 6150);
FORCEPROP 2 LAST $XR0 25E6<> 
J 0
(-11514 6150);
DISPLAY 0.638298 (-11514 6150);
PAINT MONO (-11514 6150);
FORCEPROP 2 LAST $XR1 23C3< 
J 0
(-11694 6150);
DISPLAY 0.638298 (-11694 6150);
PAINT MONO (-11694 6150);
FORCEPROP 2 LAST PATH I428
J 0
(-11250 6250);
DISPLAY 1.021277 (-11250 6250);
DISPLAY INVISIBLE (-11250 6250);
FORCEPROP 1 LAST OFFPAGE TRUE
J 2
(-11310 6205);
DISPLAY 0.808511 (-11310 6205);
PAINT GREEN (-11310 6205);
DISPLAY INVISIBLE (-11310 6205);
FORCEPROP 1 LAST BODY_TYPE COMMENT
J 2
(-11310 6285);
DISPLAY 0.808511 (-11310 6285);
PAINT GREEN (-11310 6285);
DISPLAY INVISIBLE (-11310 6285);
FORCEPROP 1 LAST CDS_LMAN_SYM_OUTLINE -50,50,50,-50
J 2
(-11300 6150);
DISPLAY 0.468085 (-11300 6150);
PAINT GREEN (-11300 6150);
DISPLAY INVISIBLE (-11300 6150);
FORCEPROP 2 LAST CDS_LIB cls
J 0
(-11300 6150);
DISPLAY INVISIBLE (-11300 6150);
FORCEADD OFFPAGE_OUT..1
R 2
(-11300 6050);
FORCEPROP 2 LAST $XR1 23C3< 
J 0
(-11694 6050);
DISPLAY 0.638298 (-11694 6050);
PAINT MONO (-11694 6050);
FORCEPROP 2 LAST $XR0 25E6<> 
J 0
(-11514 6050);
DISPLAY 0.638298 (-11514 6050);
PAINT MONO (-11514 6050);
FORCEPROP 2 LAST PATH I429
J 0
(-11250 6150);
DISPLAY 1.021277 (-11250 6150);
DISPLAY INVISIBLE (-11250 6150);
FORCEPROP 1 LAST OFFPAGE TRUE
J 2
(-11310 6105);
DISPLAY 0.808511 (-11310 6105);
PAINT GREEN (-11310 6105);
DISPLAY INVISIBLE (-11310 6105);
FORCEPROP 1 LAST BODY_TYPE COMMENT
J 2
(-11310 6185);
DISPLAY 0.808511 (-11310 6185);
PAINT GREEN (-11310 6185);
DISPLAY INVISIBLE (-11310 6185);
FORCEPROP 1 LAST CDS_LMAN_SYM_OUTLINE -50,50,50,-50
J 2
(-11300 6050);
DISPLAY 0.468085 (-11300 6050);
PAINT GREEN (-11300 6050);
DISPLAY INVISIBLE (-11300 6050);
FORCEPROP 2 LAST CDS_LIB cls
J 0
(-11300 6050);
DISPLAY INVISIBLE (-11300 6050);
FORCEADD OFFPAGE_OUT..1
R 2
(-11300 6550);
FORCEPROP 2 LAST $XR0 25E6<> 
J 0
(-11514 6550);
DISPLAY 0.638298 (-11514 6550);
PAINT MONO (-11514 6550);
FORCEPROP 2 LAST $XR1 23E3< 
J 0
(-11694 6550);
DISPLAY 0.638298 (-11694 6550);
PAINT MONO (-11694 6550);
FORCEPROP 2 LAST PATH I430
J 0
(-11250 6650);
DISPLAY 1.021277 (-11250 6650);
DISPLAY INVISIBLE (-11250 6650);
FORCEPROP 1 LAST OFFPAGE TRUE
J 2
(-11310 6605);
DISPLAY 0.808511 (-11310 6605);
PAINT GREEN (-11310 6605);
DISPLAY INVISIBLE (-11310 6605);
FORCEPROP 1 LAST BODY_TYPE COMMENT
J 2
(-11310 6685);
DISPLAY 0.808511 (-11310 6685);
PAINT GREEN (-11310 6685);
DISPLAY INVISIBLE (-11310 6685);
FORCEPROP 1 LAST CDS_LMAN_SYM_OUTLINE -50,50,50,-50
J 2
(-11300 6550);
DISPLAY 0.468085 (-11300 6550);
PAINT GREEN (-11300 6550);
DISPLAY INVISIBLE (-11300 6550);
FORCEPROP 2 LAST CDS_LIB cls
J 0
(-11300 6550);
DISPLAY INVISIBLE (-11300 6550);
FORCEADD OFFPAGE_OUT..1
R 2
(-11300 6450);
FORCEPROP 2 LAST $XR0 25F6<> 
J 0
(-11514 6450);
DISPLAY 0.638298 (-11514 6450);
PAINT MONO (-11514 6450);
FORCEPROP 2 LAST $XR1 23E3< 
J 0
(-11694 6450);
DISPLAY 0.638298 (-11694 6450);
PAINT MONO (-11694 6450);
FORCEPROP 2 LAST PATH I431
J 0
(-11250 6550);
DISPLAY 1.021277 (-11250 6550);
DISPLAY INVISIBLE (-11250 6550);
FORCEPROP 1 LAST OFFPAGE TRUE
J 2
(-11310 6505);
DISPLAY 0.808511 (-11310 6505);
PAINT GREEN (-11310 6505);
DISPLAY INVISIBLE (-11310 6505);
FORCEPROP 2 LAST CDS_LIB cls
J 0
(-11300 6450);
DISPLAY INVISIBLE (-11300 6450);
FORCEPROP 1 LAST CDS_LMAN_SYM_OUTLINE -50,50,50,-50
J 2
(-11300 6450);
DISPLAY 0.468085 (-11300 6450);
PAINT GREEN (-11300 6450);
DISPLAY INVISIBLE (-11300 6450);
FORCEPROP 1 LAST BODY_TYPE COMMENT
J 2
(-11310 6585);
DISPLAY 0.808511 (-11310 6585);
PAINT GREEN (-11310 6585);
DISPLAY INVISIBLE (-11310 6585);
FORCEADD OFFPAGE_IN..2
R 2
(-11300 4750);
FORCEPROP 2 LAST $XR0 18G13> 
J 0
(-11514 4750);
DISPLAY 0.638298 (-11514 4750);
PAINT MONO (-11514 4750);
FORCEPROP 2 LAST PATH I432
J 0
(-11500 4800);
DISPLAY 1.021277 (-11500 4800);
DISPLAY INVISIBLE (-11500 4800);
FORCEPROP 1 LAST OFFPAGE TRUE
J 2
(-11310 4805);
DISPLAY 0.808511 (-11310 4805);
PAINT GREEN (-11310 4805);
DISPLAY INVISIBLE (-11310 4805);
FORCEPROP 2 LAST CDS_LIB cls
J 0
(-11300 4750);
DISPLAY INVISIBLE (-11300 4750);
FORCEPROP 1 LAST CDS_LMAN_SYM_OUTLINE -50,50,50,-50
J 2
(-11300 4750);
DISPLAY 0.468085 (-11300 4750);
PAINT GREEN (-11300 4750);
DISPLAY INVISIBLE (-11300 4750);
FORCEPROP 1 LAST BODY_TYPE COMMENT
J 2
(-11310 4885);
DISPLAY 0.808511 (-11310 4885);
PAINT GREEN (-11310 4885);
DISPLAY INVISIBLE (-11310 4885);
FORCEADD OFFPAGE_OUT..1
R 2
(-11300 4650);
FORCEPROP 2 LAST $XR0 18G13< 
J 0
(-11514 4650);
DISPLAY 0.638298 (-11514 4650);
PAINT MONO (-11514 4650);
FORCEPROP 2 LAST PATH I433
J 0
(-11500 4700);
DISPLAY 1.021277 (-11500 4700);
DISPLAY INVISIBLE (-11500 4700);
FORCEPROP 1 LAST OFFPAGE TRUE
J 2
(-11310 4705);
DISPLAY 0.808511 (-11310 4705);
PAINT GREEN (-11310 4705);
DISPLAY INVISIBLE (-11310 4705);
FORCEPROP 2 LAST CDS_LIB cls
J 0
(-11300 4650);
DISPLAY INVISIBLE (-11300 4650);
FORCEPROP 1 LAST CDS_LMAN_SYM_OUTLINE -50,50,50,-50
J 2
(-11300 4650);
DISPLAY 0.468085 (-11300 4650);
PAINT GREEN (-11300 4650);
DISPLAY INVISIBLE (-11300 4650);
FORCEPROP 1 LAST BODY_TYPE COMMENT
J 2
(-11310 4785);
DISPLAY 0.808511 (-11310 4785);
PAINT GREEN (-11310 4785);
DISPLAY INVISIBLE (-11310 4785);
FORCEADD OFFPAGE_OUT..1
R 2
(-11300 3150);
FORCEPROP 2 LAST $XR0 25E6<> 
J 0
(-11514 3150);
DISPLAY 0.638298 (-11514 3150);
PAINT MONO (-11514 3150);
FORCEPROP 2 LAST $XR1 23J3< 
J 0
(-11694 3150);
DISPLAY 0.638298 (-11694 3150);
PAINT MONO (-11694 3150);
FORCEPROP 2 LAST PATH I434
J 0
(-11250 3250);
DISPLAY 1.021277 (-11250 3250);
DISPLAY INVISIBLE (-11250 3250);
FORCEPROP 1 LAST OFFPAGE TRUE
J 2
(-11310 3205);
DISPLAY 0.808511 (-11310 3205);
PAINT GREEN (-11310 3205);
DISPLAY INVISIBLE (-11310 3205);
FORCEPROP 2 LAST CDS_LIB cls
J 0
(-11300 3150);
DISPLAY INVISIBLE (-11300 3150);
FORCEPROP 1 LAST CDS_LMAN_SYM_OUTLINE -50,50,50,-50
J 2
(-11300 3150);
DISPLAY 0.468085 (-11300 3150);
PAINT GREEN (-11300 3150);
DISPLAY INVISIBLE (-11300 3150);
FORCEPROP 1 LAST BODY_TYPE COMMENT
J 2
(-11310 3285);
DISPLAY 0.808511 (-11310 3285);
PAINT GREEN (-11310 3285);
DISPLAY INVISIBLE (-11310 3285);
FORCEADD OFFPAGE_OUT..1
R 2
(-11300 3050);
FORCEPROP 2 LAST $XR0 25E6<> 
J 0
(-11514 3050);
DISPLAY 0.638298 (-11514 3050);
PAINT MONO (-11514 3050);
FORCEPROP 2 LAST $XR1 23K3< 
J 0
(-11694 3050);
DISPLAY 0.638298 (-11694 3050);
PAINT MONO (-11694 3050);
FORCEPROP 2 LAST PATH I435
J 0
(-11250 3150);
DISPLAY 1.021277 (-11250 3150);
DISPLAY INVISIBLE (-11250 3150);
FORCEPROP 1 LAST OFFPAGE TRUE
J 2
(-11310 3105);
DISPLAY 0.808511 (-11310 3105);
PAINT GREEN (-11310 3105);
DISPLAY INVISIBLE (-11310 3105);
FORCEPROP 2 LAST CDS_LIB cls
J 0
(-11300 3050);
DISPLAY INVISIBLE (-11300 3050);
FORCEPROP 1 LAST CDS_LMAN_SYM_OUTLINE -50,50,50,-50
J 2
(-11300 3050);
DISPLAY 0.468085 (-11300 3050);
PAINT GREEN (-11300 3050);
DISPLAY INVISIBLE (-11300 3050);
FORCEPROP 1 LAST BODY_TYPE COMMENT
J 2
(-11310 3185);
DISPLAY 0.808511 (-11310 3185);
PAINT GREEN (-11310 3185);
DISPLAY INVISIBLE (-11310 3185);
FORCEADD OFFPAGE_OUT..1
R 2
(-11300 3250);
FORCEPROP 2 LAST $XR0 25E6<> 
J 0
(-11514 3250);
DISPLAY 0.638298 (-11514 3250);
PAINT MONO (-11514 3250);
FORCEPROP 2 LAST $XR1 23G3< 
J 0
(-11694 3250);
DISPLAY 0.638298 (-11694 3250);
PAINT MONO (-11694 3250);
FORCEPROP 2 LAST PATH I436
J 0
(-11250 3350);
DISPLAY 1.021277 (-11250 3350);
DISPLAY INVISIBLE (-11250 3350);
FORCEPROP 1 LAST OFFPAGE TRUE
J 2
(-11310 3305);
DISPLAY 0.808511 (-11310 3305);
PAINT GREEN (-11310 3305);
DISPLAY INVISIBLE (-11310 3305);
FORCEPROP 2 LAST CDS_LIB cls
J 0
(-11300 3250);
DISPLAY INVISIBLE (-11300 3250);
FORCEPROP 1 LAST CDS_LMAN_SYM_OUTLINE -50,50,50,-50
J 2
(-11300 3250);
DISPLAY 0.468085 (-11300 3250);
PAINT GREEN (-11300 3250);
DISPLAY INVISIBLE (-11300 3250);
FORCEPROP 1 LAST BODY_TYPE COMMENT
J 2
(-11310 3385);
DISPLAY 0.808511 (-11310 3385);
PAINT GREEN (-11310 3385);
DISPLAY INVISIBLE (-11310 3385);
FORCEADD OFFPAGE_OUT..1
R 2
(-11300 3350);
FORCEPROP 2 LAST $XR0 25E6<> 
J 0
(-11514 3350);
DISPLAY 0.638298 (-11514 3350);
PAINT MONO (-11514 3350);
FORCEPROP 2 LAST $XR1 23G3< 
J 0
(-11694 3350);
DISPLAY 0.638298 (-11694 3350);
PAINT MONO (-11694 3350);
FORCEPROP 2 LAST PATH I437
J 0
(-11250 3450);
DISPLAY 1.021277 (-11250 3450);
DISPLAY INVISIBLE (-11250 3450);
FORCEPROP 1 LAST OFFPAGE TRUE
J 2
(-11310 3405);
DISPLAY 0.808511 (-11310 3405);
PAINT GREEN (-11310 3405);
DISPLAY INVISIBLE (-11310 3405);
FORCEPROP 2 LAST CDS_LIB cls
J 0
(-11300 3350);
DISPLAY INVISIBLE (-11300 3350);
FORCEPROP 1 LAST CDS_LMAN_SYM_OUTLINE -50,50,50,-50
J 2
(-11300 3350);
DISPLAY 0.468085 (-11300 3350);
PAINT GREEN (-11300 3350);
DISPLAY INVISIBLE (-11300 3350);
FORCEPROP 1 LAST BODY_TYPE COMMENT
J 2
(-11310 3485);
DISPLAY 0.808511 (-11310 3485);
PAINT GREEN (-11310 3485);
DISPLAY INVISIBLE (-11310 3485);
FORCEADD OFFPAGE_OUT..1
(-4050 6850);
FORCEPROP 2 LAST $XR0 26C12> 
J 0
(-3995 6850);
DISPLAY 0.638298 (-3995 6850);
PAINT MONO (-3995 6850);
FORCEPROP 2 LAST CDS_LIB cls
J 0
(-4050 6850);
DISPLAY INVISIBLE (-4050 6850);
FORCEPROP 1 LAST CDS_LMAN_SYM_OUTLINE -50,50,50,-50
J 0
(-4050 6850);
DISPLAY 0.468085 (-4050 6850);
PAINT GREEN (-4050 6850);
DISPLAY INVISIBLE (-4050 6850);
FORCEPROP 1 LAST BODY_TYPE COMMENT
J 0
(-4040 6985);
DISPLAY 0.808511 (-4040 6985);
PAINT GREEN (-4040 6985);
DISPLAY INVISIBLE (-4040 6985);
FORCEPROP 1 LAST OFFPAGE TRUE
J 0
(-4040 6905);
DISPLAY 0.808511 (-4040 6905);
PAINT GREEN (-4040 6905);
DISPLAY INVISIBLE (-4040 6905);
FORCEPROP 2 LAST PATH I438
J 0
(-4000 6950);
DISPLAY 1.021277 (-4000 6950);
DISPLAY INVISIBLE (-4000 6950);
FORCEADD OFFPAGE_OUT..1
(-4050 6950);
FORCEPROP 2 LAST $XR0 26D12> 
J 0
(-3995 6950);
DISPLAY 0.638298 (-3995 6950);
PAINT MONO (-3995 6950);
FORCEPROP 2 LAST CDS_LIB cls
J 0
(-4050 6950);
DISPLAY INVISIBLE (-4050 6950);
FORCEPROP 1 LAST CDS_LMAN_SYM_OUTLINE -50,50,50,-50
J 0
(-4050 6950);
DISPLAY 0.468085 (-4050 6950);
PAINT GREEN (-4050 6950);
DISPLAY INVISIBLE (-4050 6950);
FORCEPROP 1 LAST BODY_TYPE COMMENT
J 0
(-4040 7085);
DISPLAY 0.808511 (-4040 7085);
PAINT GREEN (-4040 7085);
DISPLAY INVISIBLE (-4040 7085);
FORCEPROP 1 LAST OFFPAGE TRUE
J 0
(-4040 7005);
DISPLAY 0.808511 (-4040 7005);
PAINT GREEN (-4040 7005);
DISPLAY INVISIBLE (-4040 7005);
FORCEPROP 2 LAST PATH I439
J 0
(-4000 7050);
DISPLAY 1.021277 (-4000 7050);
DISPLAY INVISIBLE (-4000 7050);
FORCEADD OFFPAGE_OUT..1
(-4050 6750);
FORCEPROP 2 LAST $XR0 26D12> 
J 0
(-3995 6750);
DISPLAY 0.638298 (-3995 6750);
PAINT MONO (-3995 6750);
FORCEPROP 2 LAST CDS_LIB cls
J 0
(-4050 6750);
DISPLAY INVISIBLE (-4050 6750);
FORCEPROP 1 LAST CDS_LMAN_SYM_OUTLINE -50,50,50,-50
J 0
(-4050 6750);
DISPLAY 0.468085 (-4050 6750);
PAINT GREEN (-4050 6750);
DISPLAY INVISIBLE (-4050 6750);
FORCEPROP 1 LAST BODY_TYPE COMMENT
J 0
(-4040 6885);
DISPLAY 0.808511 (-4040 6885);
PAINT GREEN (-4040 6885);
DISPLAY INVISIBLE (-4040 6885);
FORCEPROP 1 LAST OFFPAGE TRUE
J 0
(-4040 6805);
DISPLAY 0.808511 (-4040 6805);
PAINT GREEN (-4040 6805);
DISPLAY INVISIBLE (-4040 6805);
FORCEPROP 2 LAST PATH I440
J 0
(-4000 6850);
DISPLAY 1.021277 (-4000 6850);
DISPLAY INVISIBLE (-4000 6850);
FORCEADD OFFPAGE_OUT..1
(-4050 6350);
FORCEPROP 2 LAST $XR0 26E12> 
J 0
(-3995 6350);
DISPLAY 0.638298 (-3995 6350);
PAINT MONO (-3995 6350);
FORCEPROP 2 LAST CDS_LIB cls
J 0
(-4050 6350);
DISPLAY INVISIBLE (-4050 6350);
FORCEPROP 1 LAST CDS_LMAN_SYM_OUTLINE -50,50,50,-50
J 0
(-4050 6350);
DISPLAY 0.468085 (-4050 6350);
PAINT GREEN (-4050 6350);
DISPLAY INVISIBLE (-4050 6350);
FORCEPROP 1 LAST BODY_TYPE COMMENT
J 0
(-4040 6485);
DISPLAY 0.808511 (-4040 6485);
PAINT GREEN (-4040 6485);
DISPLAY INVISIBLE (-4040 6485);
FORCEPROP 1 LAST OFFPAGE TRUE
J 0
(-4040 6405);
DISPLAY 0.808511 (-4040 6405);
PAINT GREEN (-4040 6405);
DISPLAY INVISIBLE (-4040 6405);
FORCEPROP 2 LAST PATH I441
J 0
(-4000 6450);
DISPLAY 1.021277 (-4000 6450);
DISPLAY INVISIBLE (-4000 6450);
FORCEADD OFFPAGE_OUT..1
(-4050 6550);
FORCEPROP 2 LAST $XR0 26F12> 
J 0
(-3995 6550);
DISPLAY 0.638298 (-3995 6550);
PAINT MONO (-3995 6550);
FORCEPROP 2 LAST CDS_LIB cls
J 0
(-4050 6550);
DISPLAY INVISIBLE (-4050 6550);
FORCEPROP 1 LAST CDS_LMAN_SYM_OUTLINE -50,50,50,-50
J 0
(-4050 6550);
DISPLAY 0.468085 (-4050 6550);
PAINT GREEN (-4050 6550);
DISPLAY INVISIBLE (-4050 6550);
FORCEPROP 1 LAST BODY_TYPE COMMENT
J 0
(-4040 6685);
DISPLAY 0.808511 (-4040 6685);
PAINT GREEN (-4040 6685);
DISPLAY INVISIBLE (-4040 6685);
FORCEPROP 1 LAST OFFPAGE TRUE
J 0
(-4040 6605);
DISPLAY 0.808511 (-4040 6605);
PAINT GREEN (-4040 6605);
DISPLAY INVISIBLE (-4040 6605);
FORCEPROP 2 LAST PATH I442
J 0
(-4000 6650);
DISPLAY 1.021277 (-4000 6650);
DISPLAY INVISIBLE (-4000 6650);
FORCEADD OFFPAGE_OUT..1
(-4050 6450);
FORCEPROP 2 LAST $XR0 26E12> 
J 0
(-3995 6450);
DISPLAY 0.638298 (-3995 6450);
PAINT MONO (-3995 6450);
FORCEPROP 2 LAST CDS_LIB cls
J 0
(-4050 6450);
DISPLAY INVISIBLE (-4050 6450);
FORCEPROP 1 LAST CDS_LMAN_SYM_OUTLINE -50,50,50,-50
J 0
(-4050 6450);
DISPLAY 0.468085 (-4050 6450);
PAINT GREEN (-4050 6450);
DISPLAY INVISIBLE (-4050 6450);
FORCEPROP 1 LAST BODY_TYPE COMMENT
J 0
(-4040 6585);
DISPLAY 0.808511 (-4040 6585);
PAINT GREEN (-4040 6585);
DISPLAY INVISIBLE (-4040 6585);
FORCEPROP 1 LAST OFFPAGE TRUE
J 0
(-4040 6505);
DISPLAY 0.808511 (-4040 6505);
PAINT GREEN (-4040 6505);
DISPLAY INVISIBLE (-4040 6505);
FORCEPROP 2 LAST PATH I443
J 0
(-4000 6550);
DISPLAY 1.021277 (-4000 6550);
DISPLAY INVISIBLE (-4000 6550);
FORCEADD OFFPAGE_OUT..1
(-4050 4650);
FORCEPROP 2 LAST $XR0 26G12> 
J 0
(-3995 4650);
DISPLAY 0.638298 (-3995 4650);
PAINT MONO (-3995 4650);
FORCEPROP 1 LAST BODY_TYPE COMMENT
J 0
(-4040 4785);
DISPLAY 0.808511 (-4040 4785);
PAINT GREEN (-4040 4785);
DISPLAY INVISIBLE (-4040 4785);
FORCEPROP 1 LAST CDS_LMAN_SYM_OUTLINE -50,50,50,-50
J 0
(-4050 4650);
DISPLAY 0.468085 (-4050 4650);
PAINT GREEN (-4050 4650);
DISPLAY INVISIBLE (-4050 4650);
FORCEPROP 2 LAST CDS_LIB cls
J 0
(-4050 4650);
DISPLAY INVISIBLE (-4050 4650);
FORCEPROP 1 LAST OFFPAGE TRUE
J 0
(-4040 4705);
DISPLAY 0.808511 (-4040 4705);
PAINT GREEN (-4040 4705);
DISPLAY INVISIBLE (-4040 4705);
FORCEPROP 2 LAST PATH I444
J 0
(-4000 4750);
DISPLAY 1.021277 (-4000 4750);
DISPLAY INVISIBLE (-4000 4750);
FORCEADD OFFPAGE_OUT..1
(-4050 4750);
FORCEPROP 2 LAST $XR0 26G12> 
J 0
(-3995 4750);
DISPLAY 0.638298 (-3995 4750);
PAINT MONO (-3995 4750);
FORCEPROP 1 LAST BODY_TYPE COMMENT
J 0
(-4040 4885);
DISPLAY 0.808511 (-4040 4885);
PAINT GREEN (-4040 4885);
DISPLAY INVISIBLE (-4040 4885);
FORCEPROP 1 LAST CDS_LMAN_SYM_OUTLINE -50,50,50,-50
J 0
(-4050 4750);
DISPLAY 0.468085 (-4050 4750);
PAINT GREEN (-4050 4750);
DISPLAY INVISIBLE (-4050 4750);
FORCEPROP 2 LAST CDS_LIB cls
J 0
(-4050 4750);
DISPLAY INVISIBLE (-4050 4750);
FORCEPROP 1 LAST OFFPAGE TRUE
J 0
(-4040 4805);
DISPLAY 0.808511 (-4040 4805);
PAINT GREEN (-4040 4805);
DISPLAY INVISIBLE (-4040 4805);
FORCEPROP 2 LAST PATH I445
J 0
(-4000 4850);
DISPLAY 1.021277 (-4000 4850);
DISPLAY INVISIBLE (-4000 4850);
FORCEADD OFFPAGE_OUT..1
(-4050 4550);
FORCEPROP 2 LAST $XR0 26G12> 
J 0
(-3995 4550);
DISPLAY 0.638298 (-3995 4550);
PAINT MONO (-3995 4550);
FORCEPROP 1 LAST BODY_TYPE COMMENT
J 0
(-4040 4685);
DISPLAY 0.808511 (-4040 4685);
PAINT GREEN (-4040 4685);
DISPLAY INVISIBLE (-4040 4685);
FORCEPROP 1 LAST CDS_LMAN_SYM_OUTLINE -50,50,50,-50
J 0
(-4050 4550);
DISPLAY 0.468085 (-4050 4550);
PAINT GREEN (-4050 4550);
DISPLAY INVISIBLE (-4050 4550);
FORCEPROP 2 LAST CDS_LIB cls
J 0
(-4050 4550);
DISPLAY INVISIBLE (-4050 4550);
FORCEPROP 1 LAST OFFPAGE TRUE
J 0
(-4040 4605);
DISPLAY 0.808511 (-4040 4605);
PAINT GREEN (-4040 4605);
DISPLAY INVISIBLE (-4040 4605);
FORCEPROP 2 LAST PATH I446
J 0
(-4000 4650);
DISPLAY 1.021277 (-4000 4650);
DISPLAY INVISIBLE (-4000 4650);
FORCEADD OFFPAGE_OUT..1
(-4050 4250);
FORCEPROP 2 LAST $XR0 26H12> 
J 0
(-3995 4250);
DISPLAY 0.638298 (-3995 4250);
PAINT MONO (-3995 4250);
FORCEPROP 1 LAST BODY_TYPE COMMENT
J 0
(-4040 4385);
DISPLAY 0.808511 (-4040 4385);
PAINT GREEN (-4040 4385);
DISPLAY INVISIBLE (-4040 4385);
FORCEPROP 1 LAST CDS_LMAN_SYM_OUTLINE -50,50,50,-50
J 0
(-4050 4250);
DISPLAY 0.468085 (-4050 4250);
PAINT GREEN (-4050 4250);
DISPLAY INVISIBLE (-4050 4250);
FORCEPROP 2 LAST CDS_LIB cls
J 0
(-4050 4250);
DISPLAY INVISIBLE (-4050 4250);
FORCEPROP 1 LAST OFFPAGE TRUE
J 0
(-4040 4305);
DISPLAY 0.808511 (-4040 4305);
PAINT GREEN (-4040 4305);
DISPLAY INVISIBLE (-4040 4305);
FORCEPROP 2 LAST PATH I447
J 0
(-4000 4350);
DISPLAY 1.021277 (-4000 4350);
DISPLAY INVISIBLE (-4000 4350);
FORCEADD OFFPAGE_OUT..1
(-4050 4350);
FORCEPROP 2 LAST $XR0 26J12> 
J 0
(-3995 4350);
DISPLAY 0.638298 (-3995 4350);
PAINT MONO (-3995 4350);
FORCEPROP 1 LAST BODY_TYPE COMMENT
J 0
(-4040 4485);
DISPLAY 0.808511 (-4040 4485);
PAINT GREEN (-4040 4485);
DISPLAY INVISIBLE (-4040 4485);
FORCEPROP 1 LAST CDS_LMAN_SYM_OUTLINE -50,50,50,-50
J 0
(-4050 4350);
DISPLAY 0.468085 (-4050 4350);
PAINT GREEN (-4050 4350);
DISPLAY INVISIBLE (-4050 4350);
FORCEPROP 2 LAST CDS_LIB cls
J 0
(-4050 4350);
DISPLAY INVISIBLE (-4050 4350);
FORCEPROP 1 LAST OFFPAGE TRUE
J 0
(-4040 4405);
DISPLAY 0.808511 (-4040 4405);
PAINT GREEN (-4040 4405);
DISPLAY INVISIBLE (-4040 4405);
FORCEPROP 2 LAST PATH I448
J 0
(-4000 4450);
DISPLAY 1.021277 (-4000 4450);
DISPLAY INVISIBLE (-4000 4450);
FORCEADD OFFPAGE_OUT..1
(-4050 4150);
FORCEPROP 2 LAST $XR0 26H12> 
J 0
(-3995 4150);
DISPLAY 0.638298 (-3995 4150);
PAINT MONO (-3995 4150);
FORCEPROP 1 LAST BODY_TYPE COMMENT
J 0
(-4040 4285);
DISPLAY 0.808511 (-4040 4285);
PAINT GREEN (-4040 4285);
DISPLAY INVISIBLE (-4040 4285);
FORCEPROP 1 LAST CDS_LMAN_SYM_OUTLINE -50,50,50,-50
J 0
(-4050 4150);
DISPLAY 0.468085 (-4050 4150);
PAINT GREEN (-4050 4150);
DISPLAY INVISIBLE (-4050 4150);
FORCEPROP 2 LAST CDS_LIB cls
J 0
(-4050 4150);
DISPLAY INVISIBLE (-4050 4150);
FORCEPROP 1 LAST OFFPAGE TRUE
J 0
(-4040 4205);
DISPLAY 0.808511 (-4040 4205);
PAINT GREEN (-4040 4205);
DISPLAY INVISIBLE (-4040 4205);
FORCEPROP 2 LAST PATH I449
J 0
(-4000 4250);
DISPLAY 1.021277 (-4000 4250);
DISPLAY INVISIBLE (-4000 4250);
FORCEADD OFFPAGE_OUT..1
(-4050 3850);
FORCEPROP 2 LAST $XR0 26K12> 
J 0
(-3995 3850);
DISPLAY 0.638298 (-3995 3850);
PAINT MONO (-3995 3850);
FORCEPROP 1 LAST BODY_TYPE COMMENT
J 0
(-4040 3985);
DISPLAY 0.808511 (-4040 3985);
PAINT GREEN (-4040 3985);
DISPLAY INVISIBLE (-4040 3985);
FORCEPROP 1 LAST CDS_LMAN_SYM_OUTLINE -50,50,50,-50
J 0
(-4050 3850);
DISPLAY 0.468085 (-4050 3850);
PAINT GREEN (-4050 3850);
DISPLAY INVISIBLE (-4050 3850);
FORCEPROP 2 LAST CDS_LIB cls
J 0
(-4050 3850);
DISPLAY INVISIBLE (-4050 3850);
FORCEPROP 1 LAST OFFPAGE TRUE
J 0
(-4040 3905);
DISPLAY 0.808511 (-4040 3905);
PAINT GREEN (-4040 3905);
DISPLAY INVISIBLE (-4040 3905);
FORCEPROP 2 LAST PATH I450
J 0
(-4000 3950);
DISPLAY 1.021277 (-4000 3950);
DISPLAY INVISIBLE (-4000 3950);
FORCEADD OFFPAGE_OUT..1
(-4050 3950);
FORCEPROP 2 LAST $XR0 26K12> 
J 0
(-3995 3950);
DISPLAY 0.638298 (-3995 3950);
PAINT MONO (-3995 3950);
FORCEPROP 1 LAST BODY_TYPE COMMENT
J 0
(-4040 4085);
DISPLAY 0.808511 (-4040 4085);
PAINT GREEN (-4040 4085);
DISPLAY INVISIBLE (-4040 4085);
FORCEPROP 1 LAST CDS_LMAN_SYM_OUTLINE -50,50,50,-50
J 0
(-4050 3950);
DISPLAY 0.468085 (-4050 3950);
PAINT GREEN (-4050 3950);
DISPLAY INVISIBLE (-4050 3950);
FORCEPROP 2 LAST CDS_LIB cls
J 0
(-4050 3950);
DISPLAY INVISIBLE (-4050 3950);
FORCEPROP 1 LAST OFFPAGE TRUE
J 0
(-4040 4005);
DISPLAY 0.808511 (-4040 4005);
PAINT GREEN (-4040 4005);
DISPLAY INVISIBLE (-4040 4005);
FORCEPROP 2 LAST PATH I451
J 0
(-4000 4050);
DISPLAY 1.021277 (-4000 4050);
DISPLAY INVISIBLE (-4000 4050);
FORCEADD OFFPAGE_OUT..1
(-4050 3750);
FORCEPROP 2 LAST $XR0 26K12> 
J 0
(-3995 3750);
DISPLAY 0.638298 (-3995 3750);
PAINT MONO (-3995 3750);
FORCEPROP 1 LAST BODY_TYPE COMMENT
J 0
(-4040 3885);
DISPLAY 0.808511 (-4040 3885);
PAINT GREEN (-4040 3885);
DISPLAY INVISIBLE (-4040 3885);
FORCEPROP 1 LAST CDS_LMAN_SYM_OUTLINE -50,50,50,-50
J 0
(-4050 3750);
DISPLAY 0.468085 (-4050 3750);
PAINT GREEN (-4050 3750);
DISPLAY INVISIBLE (-4050 3750);
FORCEPROP 2 LAST CDS_LIB cls
J 0
(-4050 3750);
DISPLAY INVISIBLE (-4050 3750);
FORCEPROP 1 LAST OFFPAGE TRUE
J 0
(-4040 3805);
DISPLAY 0.808511 (-4040 3805);
PAINT GREEN (-4040 3805);
DISPLAY INVISIBLE (-4040 3805);
FORCEPROP 2 LAST PATH I452
J 0
(-4000 3850);
DISPLAY 1.021277 (-4000 3850);
DISPLAY INVISIBLE (-4000 3850);
FORCEADD OFFPAGE_OUT..1
R 2
(-11300 2850);
FORCEPROP 2 LAST $XR0 20F15< 
J 0
(-11514 2850);
DISPLAY 0.638298 (-11514 2850);
PAINT MONO (-11514 2850);
FORCEPROP 2 LAST PATH I453
J 0
(-11450 2900);
DISPLAY 1.021277 (-11450 2900);
DISPLAY INVISIBLE (-11450 2900);
FORCEPROP 1 LAST OFFPAGE TRUE
J 2
(-11310 2905);
DISPLAY 0.808511 (-11310 2905);
PAINT GREEN (-11310 2905);
DISPLAY INVISIBLE (-11310 2905);
FORCEPROP 2 LAST CDS_LIB cls
J 0
(-11300 2850);
DISPLAY INVISIBLE (-11300 2850);
FORCEPROP 1 LAST CDS_LMAN_SYM_OUTLINE -50,50,50,-50
J 2
(-11300 2850);
DISPLAY 0.468085 (-11300 2850);
PAINT GREEN (-11300 2850);
DISPLAY INVISIBLE (-11300 2850);
FORCEPROP 1 LAST BODY_TYPE COMMENT
J 2
(-11310 2985);
DISPLAY 0.808511 (-11310 2985);
PAINT GREEN (-11310 2985);
DISPLAY INVISIBLE (-11310 2985);
FORCEADD OFFPAGE_IN..2
R 2
(-11300 2750);
FORCEPROP 2 LAST $XR0 20F2> 
J 0
(-11483 2750);
DISPLAY 0.638298 (-11483 2750);
PAINT MONO (-11483 2750);
FORCEPROP 2 LAST PATH I454
J 0
(-11450 2800);
DISPLAY 1.021277 (-11450 2800);
DISPLAY INVISIBLE (-11450 2800);
FORCEPROP 1 LAST OFFPAGE TRUE
J 2
(-11310 2805);
DISPLAY 0.808511 (-11310 2805);
PAINT GREEN (-11310 2805);
DISPLAY INVISIBLE (-11310 2805);
FORCEPROP 1 LAST BODY_TYPE COMMENT
J 2
(-11310 2885);
DISPLAY 0.808511 (-11310 2885);
PAINT GREEN (-11310 2885);
DISPLAY INVISIBLE (-11310 2885);
FORCEPROP 1 LAST CDS_LMAN_SYM_OUTLINE -50,50,50,-50
J 2
(-11300 2750);
DISPLAY 0.468085 (-11300 2750);
PAINT GREEN (-11300 2750);
DISPLAY INVISIBLE (-11300 2750);
FORCEPROP 2 LAST CDS_LIB cls
J 0
(-11300 2750);
DISPLAY INVISIBLE (-11300 2750);
FORCEADD OFFPAGE_OUT..1
R 2
(-11300 2650);
FORCEPROP 2 LAST $XR0 20F2< 
J 0
(-11483 2650);
DISPLAY 0.638298 (-11483 2650);
PAINT MONO (-11483 2650);
FORCEPROP 2 LAST PATH I455
J 0
(-11450 2700);
DISPLAY 1.021277 (-11450 2700);
DISPLAY INVISIBLE (-11450 2700);
FORCEPROP 1 LAST OFFPAGE TRUE
J 2
(-11310 2705);
DISPLAY 0.808511 (-11310 2705);
PAINT GREEN (-11310 2705);
DISPLAY INVISIBLE (-11310 2705);
FORCEPROP 1 LAST CDS_LMAN_SYM_OUTLINE -50,50,50,-50
J 2
(-11300 2650);
DISPLAY 0.468085 (-11300 2650);
PAINT GREEN (-11300 2650);
DISPLAY INVISIBLE (-11300 2650);
FORCEPROP 2 LAST CDS_LIB cls
J 0
(-11300 2650);
DISPLAY INVISIBLE (-11300 2650);
FORCEPROP 1 LAST BODY_TYPE COMMENT
J 2
(-11310 2785);
DISPLAY 0.808511 (-11310 2785);
PAINT GREEN (-11310 2785);
DISPLAY INVISIBLE (-11310 2785);
FORCEADD OFFPAGE_OUT..1
R 2
(-11300 2450);
FORCEPROP 2 LAST $XR0 9K3< 
J 0
(-11452 2450);
DISPLAY 0.638298 (-11452 2450);
PAINT MONO (-11452 2450);
FORCEPROP 2 LAST PATH I456
J 0
(-11450 2500);
DISPLAY 1.021277 (-11450 2500);
DISPLAY INVISIBLE (-11450 2500);
FORCEPROP 1 LAST OFFPAGE TRUE
J 2
(-11310 2505);
DISPLAY 0.808511 (-11310 2505);
PAINT GREEN (-11310 2505);
DISPLAY INVISIBLE (-11310 2505);
FORCEPROP 2 LAST CDS_LIB cls
J 0
(-11300 2450);
DISPLAY INVISIBLE (-11300 2450);
FORCEPROP 1 LAST CDS_LMAN_SYM_OUTLINE -50,50,50,-50
J 2
(-11300 2450);
DISPLAY 0.468085 (-11300 2450);
PAINT GREEN (-11300 2450);
DISPLAY INVISIBLE (-11300 2450);
FORCEPROP 1 LAST BODY_TYPE COMMENT
J 2
(-11310 2585);
DISPLAY 0.808511 (-11310 2585);
PAINT GREEN (-11310 2585);
DISPLAY INVISIBLE (-11310 2585);
FORCEADD OFFPAGE_OUT..1
R 2
(-11300 6950);
FORCEPROP 2 LAST $XR0 24J5< 
J 0
(-11483 6950);
DISPLAY 0.638298 (-11483 6950);
PAINT MONO (-11483 6950);
FORCEPROP 2 LAST PATH I473
J 0
(-11250 7050);
DISPLAY 1.021277 (-11250 7050);
DISPLAY INVISIBLE (-11250 7050);
FORCEPROP 1 LAST OFFPAGE TRUE
J 2
(-11310 7005);
DISPLAY 0.808511 (-11310 7005);
PAINT GREEN (-11310 7005);
DISPLAY INVISIBLE (-11310 7005);
FORCEPROP 1 LAST BODY_TYPE COMMENT
J 2
(-11310 7085);
DISPLAY 0.808511 (-11310 7085);
PAINT GREEN (-11310 7085);
DISPLAY INVISIBLE (-11310 7085);
FORCEPROP 2 LAST CDS_LIB cls
J 0
(-11300 6950);
DISPLAY INVISIBLE (-11300 6950);
FORCEPROP 1 LAST CDS_LMAN_SYM_OUTLINE -50,50,50,-50
J 2
(-11300 6950);
DISPLAY 0.468085 (-11300 6950);
PAINT GREEN (-11300 6950);
DISPLAY INVISIBLE (-11300 6950);
FORCEADD OFFPAGE_OUT..1
R 2
(-11300 6850);
FORCEPROP 2 LAST $XR0 24J6< 
J 0
(-11483 6850);
DISPLAY 0.638298 (-11483 6850);
PAINT MONO (-11483 6850);
FORCEPROP 2 LAST PATH I474
J 0
(-11250 6950);
DISPLAY 1.021277 (-11250 6950);
DISPLAY INVISIBLE (-11250 6950);
FORCEPROP 1 LAST OFFPAGE TRUE
J 2
(-11310 6905);
DISPLAY 0.808511 (-11310 6905);
PAINT GREEN (-11310 6905);
DISPLAY INVISIBLE (-11310 6905);
FORCEPROP 1 LAST BODY_TYPE COMMENT
J 2
(-11310 6985);
DISPLAY 0.808511 (-11310 6985);
PAINT GREEN (-11310 6985);
DISPLAY INVISIBLE (-11310 6985);
FORCEPROP 2 LAST CDS_LIB cls
J 0
(-11300 6850);
DISPLAY INVISIBLE (-11300 6850);
FORCEPROP 1 LAST CDS_LMAN_SYM_OUTLINE -50,50,50,-50
J 2
(-11300 6850);
DISPLAY 0.468085 (-11300 6850);
PAINT GREEN (-11300 6850);
DISPLAY INVISIBLE (-11300 6850);
FORCEADD OFFPAGE_OUT..1
R 2
(-11300 6750);
FORCEPROP 2 LAST $XR0 24J12< 
J 0
(-11514 6750);
DISPLAY 0.638298 (-11514 6750);
PAINT MONO (-11514 6750);
FORCEPROP 2 LAST PATH I475
J 0
(-11250 6850);
DISPLAY 1.021277 (-11250 6850);
DISPLAY INVISIBLE (-11250 6850);
FORCEPROP 1 LAST OFFPAGE TRUE
J 2
(-11310 6805);
DISPLAY 0.808511 (-11310 6805);
PAINT GREEN (-11310 6805);
DISPLAY INVISIBLE (-11310 6805);
FORCEPROP 2 LAST CDS_LIB cls
J 0
(-11300 6750);
DISPLAY INVISIBLE (-11300 6750);
FORCEPROP 1 LAST CDS_LMAN_SYM_OUTLINE -50,50,50,-50
J 2
(-11300 6750);
DISPLAY 0.468085 (-11300 6750);
PAINT GREEN (-11300 6750);
DISPLAY INVISIBLE (-11300 6750);
FORCEPROP 1 LAST BODY_TYPE COMMENT
J 2
(-11310 6885);
DISPLAY 0.808511 (-11310 6885);
PAINT GREEN (-11310 6885);
DISPLAY INVISIBLE (-11310 6885);
FORCEADD OFFPAGE_BI..1
R 4
(-11300 5050);
FORCEPROP 2 LAST $XR0 25J7<> 
J 0
(-11550 5050);
DISPLAY 0.638298 (-11550 5050);
PAINT MONO (-11550 5050);
FORCEPROP 2 LAST $XR1 25K5<> 
J 0
(-11760 5050);
DISPLAY 0.638298 (-11760 5050);
PAINT MONO (-11760 5050);
FORCEPROP 1 LAST OFFPAGE TRUE
R 2
J 0
(-11310 4995);
DISPLAY 0.808511 (-11310 4995);
PAINT GREEN (-11310 4995);
DISPLAY INVISIBLE (-11310 4995);
FORCEPROP 1 LAST BODY_TYPE COMMENT
R 2
J 0
(-11310 4915);
DISPLAY 0.808511 (-11310 4915);
PAINT GREEN (-11310 4915);
DISPLAY INVISIBLE (-11310 4915);
FORCEPROP 1 LAST CDS_LMAN_SYM_OUTLINE -50,50,50,-50
R 2
J 0
(-11300 5050);
DISPLAY 0.468085 (-11300 5050);
PAINT GREEN (-11300 5050);
DISPLAY INVISIBLE (-11300 5050);
FORCEPROP 2 LAST PATH I476
J 0
(-11250 5150);
DISPLAY 1.021277 (-11250 5150);
DISPLAY INVISIBLE (-11250 5150);
FORCEPROP 2 LAST CDS_LIB cls
J 0
(-11300 5050);
DISPLAY INVISIBLE (-11300 5050);
FORCEADD OFFPAGE_BI..1
R 4
(-11300 5750);
FORCEPROP 2 LAST $XR0 25H5<> 
J 0
(-11519 5750);
DISPLAY 0.638298 (-11519 5750);
PAINT MONO (-11519 5750);
FORCEPROP 2 LAST $XR1 25J12<> 
J 0
(-11729 5750);
DISPLAY 0.638298 (-11729 5750);
PAINT MONO (-11729 5750);
FORCEPROP 1 LAST OFFPAGE TRUE
R 2
J 0
(-11310 5695);
DISPLAY 0.808511 (-11310 5695);
PAINT GREEN (-11310 5695);
DISPLAY INVISIBLE (-11310 5695);
FORCEPROP 1 LAST BODY_TYPE COMMENT
R 2
J 0
(-11310 5615);
DISPLAY 0.808511 (-11310 5615);
PAINT GREEN (-11310 5615);
DISPLAY INVISIBLE (-11310 5615);
FORCEPROP 1 LAST CDS_LMAN_SYM_OUTLINE -50,50,50,-50
R 2
J 0
(-11300 5750);
DISPLAY 0.468085 (-11300 5750);
PAINT GREEN (-11300 5750);
DISPLAY INVISIBLE (-11300 5750);
FORCEPROP 2 LAST PATH I477
J 0
(-11250 5850);
DISPLAY 1.021277 (-11250 5850);
DISPLAY INVISIBLE (-11250 5850);
FORCEPROP 2 LAST CDS_LIB cls
J 0
(-11300 5750);
DISPLAY INVISIBLE (-11300 5750);
FORCEADD OFFPAGE_BI..1
R 4
(-11300 5650);
FORCEPROP 2 LAST $XR0 25J12<> 
J 0
(-11550 5650);
DISPLAY 0.638298 (-11550 5650);
PAINT MONO (-11550 5650);
FORCEPROP 2 LAST $XR1 25J5<> 
J 0
(-11760 5650);
DISPLAY 0.638298 (-11760 5650);
PAINT MONO (-11760 5650);
FORCEPROP 1 LAST OFFPAGE TRUE
R 2
J 0
(-11310 5595);
DISPLAY 0.808511 (-11310 5595);
PAINT GREEN (-11310 5595);
DISPLAY INVISIBLE (-11310 5595);
FORCEPROP 1 LAST BODY_TYPE COMMENT
R 2
J 0
(-11310 5515);
DISPLAY 0.808511 (-11310 5515);
PAINT GREEN (-11310 5515);
DISPLAY INVISIBLE (-11310 5515);
FORCEPROP 1 LAST CDS_LMAN_SYM_OUTLINE -50,50,50,-50
R 2
J 0
(-11300 5650);
DISPLAY 0.468085 (-11300 5650);
PAINT GREEN (-11300 5650);
DISPLAY INVISIBLE (-11300 5650);
FORCEPROP 2 LAST PATH I478
J 0
(-11250 5750);
DISPLAY 1.021277 (-11250 5750);
DISPLAY INVISIBLE (-11250 5750);
FORCEPROP 2 LAST CDS_LIB cls
J 0
(-11300 5650);
DISPLAY INVISIBLE (-11300 5650);
FORCEADD OFFPAGE_BI..1
R 4
(-11300 5550);
FORCEPROP 2 LAST $XR0 25J12<> 
J 0
(-11519 5550);
DISPLAY 0.638298 (-11519 5550);
PAINT MONO (-11519 5550);
FORCEPROP 2 LAST $XR1 25J5<> 
J 0
(-11729 5550);
DISPLAY 0.638298 (-11729 5550);
PAINT MONO (-11729 5550);
FORCEPROP 1 LAST OFFPAGE TRUE
R 2
J 0
(-11310 5495);
DISPLAY 0.808511 (-11310 5495);
PAINT GREEN (-11310 5495);
DISPLAY INVISIBLE (-11310 5495);
FORCEPROP 1 LAST BODY_TYPE COMMENT
R 2
J 0
(-11310 5415);
DISPLAY 0.808511 (-11310 5415);
PAINT GREEN (-11310 5415);
DISPLAY INVISIBLE (-11310 5415);
FORCEPROP 1 LAST CDS_LMAN_SYM_OUTLINE -50,50,50,-50
R 2
J 0
(-11300 5550);
DISPLAY 0.468085 (-11300 5550);
PAINT GREEN (-11300 5550);
DISPLAY INVISIBLE (-11300 5550);
FORCEPROP 2 LAST PATH I479
J 0
(-11250 5650);
DISPLAY 1.021277 (-11250 5650);
DISPLAY INVISIBLE (-11250 5650);
FORCEPROP 2 LAST CDS_LIB cls
J 0
(-11300 5550);
DISPLAY INVISIBLE (-11300 5550);
FORCEADD OFFPAGE_BI..1
R 4
(-11300 5450);
FORCEPROP 2 LAST $XR1 25J5<> 
J 0
(-11760 5450);
DISPLAY 0.638298 (-11760 5450);
PAINT MONO (-11760 5450);
FORCEPROP 2 LAST $XR0 25J12<> 
J 0
(-11550 5450);
DISPLAY 0.638298 (-11550 5450);
PAINT MONO (-11550 5450);
FORCEPROP 1 LAST OFFPAGE TRUE
R 2
J 0
(-11310 5395);
DISPLAY 0.808511 (-11310 5395);
PAINT GREEN (-11310 5395);
DISPLAY INVISIBLE (-11310 5395);
FORCEPROP 1 LAST BODY_TYPE COMMENT
R 2
J 0
(-11310 5315);
DISPLAY 0.808511 (-11310 5315);
PAINT GREEN (-11310 5315);
DISPLAY INVISIBLE (-11310 5315);
FORCEPROP 1 LAST CDS_LMAN_SYM_OUTLINE -50,50,50,-50
R 2
J 0
(-11300 5450);
DISPLAY 0.468085 (-11300 5450);
PAINT GREEN (-11300 5450);
DISPLAY INVISIBLE (-11300 5450);
FORCEPROP 2 LAST PATH I480
J 0
(-11250 5550);
DISPLAY 1.021277 (-11250 5550);
DISPLAY INVISIBLE (-11250 5550);
FORCEPROP 2 LAST CDS_LIB cls
J 0
(-11300 5450);
DISPLAY INVISIBLE (-11300 5450);
FORCEADD OFFPAGE_BI..1
R 4
(-11300 5350);
FORCEPROP 2 LAST $XR0 25J5<> 
J 0
(-11519 5350);
DISPLAY 0.638298 (-11519 5350);
PAINT MONO (-11519 5350);
FORCEPROP 2 LAST $XR1 25J7<> 
J 0
(-11729 5350);
DISPLAY 0.638298 (-11729 5350);
PAINT MONO (-11729 5350);
FORCEPROP 1 LAST OFFPAGE TRUE
R 2
J 0
(-11310 5295);
DISPLAY 0.808511 (-11310 5295);
PAINT GREEN (-11310 5295);
DISPLAY INVISIBLE (-11310 5295);
FORCEPROP 1 LAST BODY_TYPE COMMENT
R 2
J 0
(-11310 5215);
DISPLAY 0.808511 (-11310 5215);
PAINT GREEN (-11310 5215);
DISPLAY INVISIBLE (-11310 5215);
FORCEPROP 1 LAST CDS_LMAN_SYM_OUTLINE -50,50,50,-50
R 2
J 0
(-11300 5350);
DISPLAY 0.468085 (-11300 5350);
PAINT GREEN (-11300 5350);
DISPLAY INVISIBLE (-11300 5350);
FORCEPROP 2 LAST PATH I481
J 0
(-11250 5450);
DISPLAY 1.021277 (-11250 5450);
DISPLAY INVISIBLE (-11250 5450);
FORCEPROP 2 LAST CDS_LIB cls
J 0
(-11300 5350);
DISPLAY INVISIBLE (-11300 5350);
FORCEADD OFFPAGE_BI..1
R 4
(-11300 5250);
FORCEPROP 2 LAST $XR1 25K5<> 
J 0
(-11760 5250);
DISPLAY 0.638298 (-11760 5250);
PAINT MONO (-11760 5250);
FORCEPROP 2 LAST $XR0 25J7<> 
J 0
(-11550 5250);
DISPLAY 0.638298 (-11550 5250);
PAINT MONO (-11550 5250);
FORCEPROP 1 LAST OFFPAGE TRUE
R 2
J 0
(-11310 5195);
DISPLAY 0.808511 (-11310 5195);
PAINT GREEN (-11310 5195);
DISPLAY INVISIBLE (-11310 5195);
FORCEPROP 1 LAST BODY_TYPE COMMENT
R 2
J 0
(-11310 5115);
DISPLAY 0.808511 (-11310 5115);
PAINT GREEN (-11310 5115);
DISPLAY INVISIBLE (-11310 5115);
FORCEPROP 1 LAST CDS_LMAN_SYM_OUTLINE -50,50,50,-50
R 2
J 0
(-11300 5250);
DISPLAY 0.468085 (-11300 5250);
PAINT GREEN (-11300 5250);
DISPLAY INVISIBLE (-11300 5250);
FORCEPROP 2 LAST PATH I482
J 0
(-11250 5350);
DISPLAY 1.021277 (-11250 5350);
DISPLAY INVISIBLE (-11250 5350);
FORCEPROP 2 LAST CDS_LIB cls
J 0
(-11300 5250);
DISPLAY INVISIBLE (-11300 5250);
FORCEADD OFFPAGE_BI..1
R 4
(-11300 5150);
FORCEPROP 2 LAST $XR0 25J7<> 
J 0
(-11519 5150);
DISPLAY 0.638298 (-11519 5150);
PAINT MONO (-11519 5150);
FORCEPROP 2 LAST $XR1 25K5<> 
J 0
(-11729 5150);
DISPLAY 0.638298 (-11729 5150);
PAINT MONO (-11729 5150);
FORCEPROP 1 LAST OFFPAGE TRUE
R 2
J 0
(-11310 5095);
DISPLAY 0.808511 (-11310 5095);
PAINT GREEN (-11310 5095);
DISPLAY INVISIBLE (-11310 5095);
FORCEPROP 1 LAST BODY_TYPE COMMENT
R 2
J 0
(-11310 5015);
DISPLAY 0.808511 (-11310 5015);
PAINT GREEN (-11310 5015);
DISPLAY INVISIBLE (-11310 5015);
FORCEPROP 1 LAST CDS_LMAN_SYM_OUTLINE -50,50,50,-50
R 2
J 0
(-11300 5150);
DISPLAY 0.468085 (-11300 5150);
PAINT GREEN (-11300 5150);
DISPLAY INVISIBLE (-11300 5150);
FORCEPROP 2 LAST PATH I483
J 0
(-11250 5250);
DISPLAY 1.021277 (-11250 5250);
DISPLAY INVISIBLE (-11250 5250);
FORCEPROP 2 LAST CDS_LIB cls
J 0
(-11300 5150);
DISPLAY INVISIBLE (-11300 5150);
FORCEADD SHEET_A1..1
(250 -1450);
FORCEPROP 2 LAST CUSTOM_TXT_CDS <XR_PAGE_TITLE>
J 0
(-15320 9900);
DISPLAY 0.638298 (-15320 9900);
PAINT PINK (-15320 9900);
FORCEPROP 1 LAST CUSTOM_TXT_CDS <DOCNO>
J 0
(-1800 -1065);
DISPLAY 0.978723 (-1800 -1065);
FORCEPROP 1 LAST CUSTOM_TXT_CDS <CON_PAGE_NUM>
J 0
(-1905 -1400);
DISPLAY 0.978723 (-1905 -1400);
FORCEPROP 1 LAST CUSTOM_TXT_CDS <DATE>
J 0
(-450 -1275);
DISPLAY 0.978723 (-450 -1275);
FORCEPROP 1 LAST CUSTOM_TXT_CDS <TITLE>
J 1
(-1535 -820);
DISPLAY 0.978723 (-1535 -820);
FORCEPROP 1 LAST CUSTOM_TXT_CDS <DESIGNER>
J 0
(-450 -850);
DISPLAY 0.978723 (-450 -850);
FORCEPROP 1 LAST CUSTOM_TXT_CDS <CON_TOTAL_PAGES>
J 0
(-1595 -1400);
DISPLAY 0.808511 (-1595 -1400);
FORCEPROP 1 LAST CUSTOM_TXT_CDS <ASSY_PN>
J 0
(-1800 -1275);
DISPLAY 0.978723 (-1800 -1275);
FORCEPROP 1 LAST CUSTOM_TXT_CDS <DOCREV>
J 0
(-450 -1075);
DISPLAY 0.978723 (-450 -1075);
FORCEPROP 1 LAST TITLE FPGA_3/5
J 0
(-2250 -550);
DISPLAY 3.042553 (-2250 -550);
PAINT GREEN (-2250 -550);
FORCEPROP 2 LAST CDS_LIB cls
J 0
(250 -1450);
DISPLAY INVISIBLE (250 -1450);
FORCEPROP 1 LAST CDS_LMAN_SYM_OUTLINE -15850,11500,200,-200
J 0
(250 -1450);
DISPLAY 0.468085 (250 -1450);
PAINT GREEN (250 -1450);
DISPLAY INVISIBLE (250 -1450);
FORCEPROP 2 LAST PAGE_BORDER TRUE
J 0
(-15320 9900);
DISPLAY 0.638298 (-15320 9900);
PAINT PINK (-15320 9900);
DISPLAY INVISIBLE (-15320 9900);
FORCEPROP 1 LAST COMMENT_BODY TRUE
J 0
(260 -1395);
DISPLAY 0.808511 (260 -1395);
DISPLAY INVISIBLE (260 -1395);
FORCEPROP 2 LAST CDS_XR_PAGE_TITLE CR-12 : @TIMECARD_LIB.TIMECARD(SCH_1):PAGE12
J 0
(-15320 9900);
DISPLAY 0.638298 (-15320 9900);
PAINT PINK (-15320 9900);
DISPLAY INVISIBLE (-15320 9900);
WIRE 16 -1 (-9250 4150)(-11250 4150);
FORCEPROP 2 LAST SIG_NAME FPGA_IN_LM75B_INT1_N
J 0
(-11160 4160);
DISPLAY 1.021277 (-11160 4160);
WIRE 16 -1 (-9250 4050)(-11250 4050);
FORCEPROP 2 LAST SIG_NAME FPGA_IN_LM75B_INT2_N
J 0
(-11160 4060);
DISPLAY 1.021277 (-11160 4060);
WIRE 16 -1 (-9250 5150)(-11250 5150);
FORCEPROP 2 LAST SIG_NAME FPGA_IO_6
J 0
(-11160 5160);
DISPLAY 1.021277 (-11160 5160);
WIRE 16 -1 (-9250 5550)(-11250 5550);
FORCEPROP 2 LAST SIG_NAME FPGA_IO_2
J 0
(-11160 5560);
DISPLAY 1.021277 (-11160 5560);
WIRE 16 -1 (-9250 5650)(-11250 5650);
FORCEPROP 2 LAST SIG_NAME FPGA_IO_1
J 0
(-11160 5660);
DISPLAY 1.021277 (-11160 5660);
WIRE 16 -1 (-9250 5750)(-11250 5750);
FORCEPROP 2 LAST SIG_NAME FPGA_IO_0
J 0
(-11160 5760);
DISPLAY 1.021277 (-11160 5760);
WIRE 16 -1 (-9250 5350)(-11250 5350);
FORCEPROP 2 LAST SIG_NAME FPGA_IO_4
J 0
(-11160 5360);
DISPLAY 1.021277 (-11160 5360);
WIRE 16 -1 (-9250 5450)(-11250 5450);
FORCEPROP 2 LAST SIG_NAME FPGA_IO_3
J 0
(-11160 5460);
DISPLAY 1.021277 (-11160 5460);
WIRE 16 -1 (-11250 6050)(-9250 6050);
FORCEPROP 2 LAST SIG_NAME SMA3_SIG_IN_BF_EN_N
J 0
(-11160 6060);
DISPLAY 1.021277 (-11160 6060);
WIRE 16 -1 (-9250 5050)(-11250 5050);
FORCEPROP 2 LAST SIG_NAME FPGA_IO_7
J 0
(-11160 5060);
DISPLAY 1.021277 (-11160 5060);
WIRE 16 -1 (-9250 3950)(-11250 3950);
FORCEPROP 2 LAST SIG_NAME FPGA_IN_LM75B_INT3_N
J 0
(-11160 3960);
DISPLAY 1.021277 (-11160 3960);
WIRE 16 -1 (-11250 3750)(-9250 3750);
FORCEPROP 2 LAST SIG_NAME FPGA_BRD_REV2
J 0
(-11160 3760);
DISPLAY 1.021277 (-11160 3760);
WIRE 16 -1 (-11250 3650)(-9250 3650);
FORCEPROP 2 LAST SIG_NAME FPGA_BRD_REV1
J 0
(-11160 3660);
DISPLAY 1.021277 (-11160 3660);
WIRE 16 -1 (-11250 4950)(-9250 4950);
FORCEPROP 2 LAST SIG_NAME FPGA_IN_RST_DLY_N
J 0
(-11160 4960);
DISPLAY 1.021277 (-11160 4960);
WIRE 16 -1 (-11250 4750)(-9250 4750);
FORCEPROP 2 LAST SIG_NAME FPGA_IN_SHT3X_ALERT_N
J 0
(-11160 4760);
DISPLAY 1.021277 (-11160 4760);
WIRE 16 -1 (-11250 4650)(-9250 4650);
FORCEPROP 2 LAST SIG_NAME FPGA_OUT_SHT3X_RST_N
J 0
(-11160 4660);
DISPLAY 1.021277 (-11160 4660);
WIRE 16 -1 (-11250 3350)(-9250 3350);
FORCEPROP 2 LAST SIG_NAME SMA1_SIG_OUT_BF_EN_N
J 0
(-11160 3360);
DISPLAY 1.021277 (-11160 3360);
WIRE 16 -1 (-11250 6150)(-9250 6150);
FORCEPROP 2 LAST SIG_NAME SMA3_SIG_OUT_BF_EN_N
J 0
(-11160 6160);
DISPLAY 1.021277 (-11160 6160);
WIRE 16 -1 (-9250 5250)(-11250 5250);
FORCEPROP 2 LAST SIG_NAME FPGA_IO_5
J 0
(-11160 5260);
DISPLAY 1.021277 (-11160 5260);
WIRE 16 -1 (-11250 3150)(-9250 3150);
FORCEPROP 2 LAST SIG_NAME SMA2_SIG_OUT_BF_EN_N
J 0
(-11160 3160);
DISPLAY 1.021277 (-11160 3160);
WIRE 16 -1 (-11250 3250)(-9250 3250);
FORCEPROP 2 LAST SIG_NAME SMA1_SIG_IN_BF_EN_N
J 0
(-11160 3260);
DISPLAY 1.021277 (-11160 3260);
WIRE 16 -1 (-11250 3050)(-9250 3050);
FORCEPROP 2 LAST SIG_NAME SMA2_SIG_IN_BF_EN_N
J 0
(-11160 3060);
DISPLAY 1.021277 (-11160 3060);
WIRE 16 -1 (-11250 2650)(-9250 2650);
FORCEPROP 2 LAST SIG_NAME FPGA_OUT_BNO080_BOOT_N
J 0
(-11160 2660);
DISPLAY 1.021277 (-11160 2660);
WIRE 16 -1 (-11250 2450)(-9250 2450);
FORCEPROP 2 LAST SIG_NAME FPGA_OUT_I2C_BUFFER_EN
J 0
(-11160 2460);
DISPLAY 1.021277 (-11160 2460);
WIRE 16 -1 (-11250 2350)(-9250 2350);
FORCEPROP 2 LAST SIG_NAME FPGA_IN_MAC_USB_OC_N
J 0
(-11160 2360);
DISPLAY 1.021277 (-11160 2360);
WIRE 16 -1 (-11250 2250)(-9250 2250);
FORCEPROP 2 LAST SIG_NAME RSVD_DBG_USB_MUX_SEL
J 0
(-11160 2260);
DISPLAY 1.021277 (-11160 2260);
WIRE 16 -1 (-6050 3150)(-5300 3150);
FORCEPROP 2 LAST SIG_NAME IO_L20P_16
J 0
(-5860 3160);
DISPLAY 1.021277 (-5860 3160);
WIRE 16 -1 (-6050 3050)(-5300 3050);
FORCEPROP 2 LAST SIG_NAME IO_L20N_16
J 0
(-5860 3060);
DISPLAY 1.021277 (-5860 3060);
WIRE 16 -1 (-6050 2950)(-5300 2950);
FORCEPROP 2 LAST SIG_NAME IO_L21P_16
J 0
(-5860 2960);
DISPLAY 1.021277 (-5860 2960);
WIRE 16 -1 (-6050 2850)(-5300 2850);
FORCEPROP 2 LAST SIG_NAME IO_L21N_16
J 0
(-5860 2860);
DISPLAY 1.021277 (-5860 2860);
WIRE 16 -1 (-4100 6350)(-6050 6350);
FORCEPROP 2 LAST SIG_NAME FPGA_OUT_SMA2_LED_RED_N
J 0
(-5360 6360);
DISPLAY 1.021277 (-5360 6360);
WIRE 16 -1 (-6050 5950)(-4100 5950);
FORCEPROP 2 LAST SIG_NAME LED_DATOUT2
J 0
(-4760 5960);
DISPLAY 1.021277 (-4760 5960);
WIRE 16 -1 (-6050 5850)(-4100 5850);
FORCEPROP 2 LAST SIG_NAME LED_DATOUT3
J 0
(-4760 5860);
DISPLAY 1.021277 (-4760 5860);
WIRE 16 -1 (-6050 5550)(-4100 5550);
FORCEPROP 2 LAST SIG_NAME LED_DATOUT1
J 0
(-4760 5560);
DISPLAY 1.021277 (-4760 5560);
WIRE 16 -1 (-6050 5450)(-4100 5450);
FORCEPROP 2 LAST SIG_NAME LED_DATOUT0
J 0
(-4760 5460);
DISPLAY 1.021277 (-4760 5460);
WIRE 16 -1 (-6050 5150)(-4100 5150);
FORCEPROP 2 LAST SIG_NAME FPGA_USR_LED1
J 0
(-4760 5160);
DISPLAY 1.021277 (-4760 5160);
WIRE 16 -1 (-6050 3850)(-4100 3850);
FORCEPROP 2 LAST SIG_NAME FPGA_OUT_GPS_LED_GREEN_N
J 0
(-5360 3860);
DISPLAY 1.021277 (-5360 3860);
WIRE 16 -1 (-6050 3950)(-4100 3950);
FORCEPROP 2 LAST SIG_NAME FPGA_OUT_GPS_LED_BLUE_N
J 0
(-5360 3960);
DISPLAY 1.021277 (-5360 3960);
WIRE 16 -1 (-4100 4150)(-6050 4150);
FORCEPROP 2 LAST SIG_NAME FPGA_OUT_SMA4_LED_RED_N
J 0
(-5360 4160);
DISPLAY 1.021277 (-5360 4160);
WIRE 16 -1 (-11250 6950)(-9250 6950);
FORCEPROP 2 LAST SIG_NAME FPGA_OUT_MUX1_SEL
J 0
(-11160 6960);
DISPLAY 1.021277 (-11160 6960);
WIRE 16 -1 (-11250 6850)(-9250 6850);
FORCEPROP 2 LAST SIG_NAME FPGA_OUT_MUX2_SEL
J 0
(-11160 6860);
DISPLAY 1.021277 (-11160 6860);
WIRE 16 -1 (-11250 6750)(-9250 6750);
FORCEPROP 2 LAST SIG_NAME FPGA_OUT_MUX3_SEL
J 0
(-11160 6760);
DISPLAY 1.021277 (-11160 6760);
WIRE 16 -1 (-11250 6450)(-9250 6450);
FORCEPROP 2 LAST SIG_NAME SMA4_SIG_OUT_BF_EN_N
J 0
(-11160 6460);
DISPLAY 1.021277 (-11160 6460);
WIRE 16 -1 (-11250 6550)(-9250 6550);
FORCEPROP 2 LAST SIG_NAME SMA4_SIG_IN_BF_EN_N
J 0
(-11160 6560);
DISPLAY 1.021277 (-11160 6560);
WIRE 16 -1 (-6050 6950)(-4100 6950);
FORCEPROP 2 LAST SIG_NAME FPGA_OUT_SMA1_LED_BLUE_N
J 0
(-5360 6960);
DISPLAY 1.021277 (-5360 6960);
WIRE 16 -1 (-6050 6850)(-4100 6850);
FORCEPROP 2 LAST SIG_NAME FPGA_OUT_SMA1_LED_GREEN_N
J 0
(-5360 6860);
DISPLAY 1.021277 (-5360 6860);
WIRE 16 -1 (-4100 6750)(-6050 6750);
FORCEPROP 2 LAST SIG_NAME FPGA_OUT_SMA1_LED_RED_N
J 0
(-5360 6760);
DISPLAY 1.021277 (-5360 6760);
WIRE 16 -1 (-6050 6550)(-4100 6550);
FORCEPROP 2 LAST SIG_NAME FPGA_OUT_SMA2_LED_BLUE_N
J 0
(-5360 6560);
DISPLAY 1.021277 (-5360 6560);
WIRE 16 -1 (-6050 6450)(-4100 6450);
FORCEPROP 2 LAST SIG_NAME FPGA_OUT_SMA2_LED_GREEN_N
J 0
(-5360 6460);
DISPLAY 1.021277 (-5360 6460);
WIRE 16 -1 (-6050 5050)(-4100 5050);
FORCEPROP 2 LAST SIG_NAME FPGA_USR_LED0
J 0
(-4760 5060);
DISPLAY 1.021277 (-4760 5060);
WIRE 16 -1 (-6050 4750)(-4100 4750);
FORCEPROP 2 LAST SIG_NAME FPGA_OUT_SMA3_LED_BLUE_N
J 0
(-5360 4760);
DISPLAY 1.021277 (-5360 4760);
WIRE 16 -1 (-6050 4650)(-4100 4650);
FORCEPROP 2 LAST SIG_NAME FPGA_OUT_SMA3_LED_GREEN_N
J 0
(-5360 4660);
DISPLAY 1.021277 (-5360 4660);
WIRE 16 -1 (-4100 4550)(-6050 4550);
FORCEPROP 2 LAST SIG_NAME FPGA_OUT_SMA3_LED_RED_N
J 0
(-5360 4560);
DISPLAY 1.021277 (-5360 4560);
WIRE 16 -1 (-6050 4350)(-4100 4350);
FORCEPROP 2 LAST SIG_NAME FPGA_OUT_SMA4_LED_BLUE_N
J 0
(-5360 4360);
DISPLAY 1.021277 (-5360 4360);
WIRE 16 -1 (-6050 4250)(-4100 4250);
FORCEPROP 2 LAST SIG_NAME FPGA_OUT_SMA4_LED_GREEN_N
J 0
(-5360 4260);
DISPLAY 1.021277 (-5360 4260);
WIRE 16 -1 (-4100 3750)(-6050 3750);
FORCEPROP 2 LAST SIG_NAME FPGA_OUT_GPS_LED_RED_N
J 0
(-5360 3760);
DISPLAY 1.021277 (-5360 3760);
WIRE 16 -1 (-6050 2450)(-5300 2450);
FORCEPROP 2 LAST SIG_NAME IO_L23N_16
J 0
(-5860 2460);
DISPLAY 1.021277 (-5860 2460);
WIRE 16 -1 (-6050 2550)(-5300 2550);
FORCEPROP 2 LAST SIG_NAME IO_L23P_16
J 0
(-5860 2560);
DISPLAY 1.021277 (-5860 2560);
WIRE 16 -1 (-6050 2650)(-5300 2650);
FORCEPROP 2 LAST SIG_NAME IO_L22N_16
J 0
(-5860 2660);
DISPLAY 1.021277 (-5860 2660);
WIRE 16 -1 (-6050 2750)(-5300 2750);
FORCEPROP 2 LAST SIG_NAME IO_L22P_16
J 0
(-5860 2760);
DISPLAY 1.021277 (-5860 2760);
WIRE 16 -1 (-6050 2250)(-5300 2250);
FORCEPROP 2 LAST SIG_NAME IO_L24N_16
J 0
(-5860 2260);
DISPLAY 1.021277 (-5860 2260);
WIRE 16 -1 (-6050 2350)(-5300 2350);
FORCEPROP 2 LAST SIG_NAME IO_L24P_16
J 0
(-5860 2360);
DISPLAY 1.021277 (-5860 2360);
WIRE 16 -1 (-11250 3550)(-9250 3550);
FORCEPROP 2 LAST SIG_NAME FPGA_BRD_REV0
J 0
(-11160 3560);
DISPLAY 1.021277 (-11160 3560);
WIRE 16 -1 (-11250 2850)(-9250 2850);
FORCEPROP 2 LAST SIG_NAME FPGA_OUT_BNO080_RST_N
J 0
(-11160 2860);
DISPLAY 1.021277 (-11160 2860);
WIRE 16 -1 (-11250 2750)(-9250 2750);
FORCEPROP 2 LAST SIG_NAME FPGA_IN_BNO080_INT_N
J 0
(-11160 2760);
DISPLAY 1.021277 (-11160 2760);
FORCENOTE
FPGA 3/5
(-8350 8900) 0;
DISPLAY LEFT (-8350 8900);
DISPLAY 3.936170 (-8350 8900);
QUIT
